FILE_TYPE = MACRO_DRAWING;
SET COLOR_WIRE YELLOW;
SET COLOR_PROP MONO;
SET COLOR_DOT WHITE;
SET COLOR_ARC YELLOW;
SET COLOR_BODY GREEN;
SET COLOR_NOTE MONO;
SET PROP_DISPLAY VALUE;
SET PAGE_NUMBER P203;
FORCEADD CAP..1
(-6850 4175);
FORCEPROP 1 LAST LOCATION C6P24
J 0
(-6800 4275);
DISPLAY 0.617021 (-6800 4275);
PAINT AQUA (-6800 4275);
FORCEPROP 1 LAST VALUE 10UF
J 0
(-6800 4225);
DISPLAY 0.617021 (-6800 4225);
PAINT SKYBLUE (-6800 4225);
FORCEPROP 1 LAST TOLERANCE 10%
J 0
(-6800 4125);
DISPLAY 0.617021 (-6800 4125);
PAINT SKYBLUE (-6800 4125);
FORCEPROP 1 LAST VOLTAGE 16V
J 0
(-6800 4175);
DISPLAY 0.617021 (-6800 4175);
PAINT SKYBLUE (-6800 4175);
FORCEPROP 1 LASTPIN (-6850 4275) $PN 1
J 0
(-6840 4255);
DISPLAY 0.617021 (-6840 4255);
PAINT ORANGE (-6840 4255);
FORCEPROP 1 LAST MATERIAL X6S
J 0
(-6800 4075);
DISPLAY 0.617021 (-6800 4075);
PAINT SKYBLUE (-6800 4075);
FORCEPROP 1 LAST PART_NUMBER C95333-007
J 0
(-6800 4025);
DISPLAY 0.617021 (-6800 4025);
PAINT BLUE (-6800 4025);
FORCEPROP 1 LAST PACK_TYPE 0805
J 0
(-6800 3975);
DISPLAY 0.617021 (-6800 3975);
PAINT SKYBLUE (-6800 3975);
FORCEPROP 1 LASTPIN (-6850 4075) $PN 2
J 0
(-6840 4055);
DISPLAY 0.617021 (-6840 4055);
PAINT ORANGE (-6840 4055);
FORCEPROP 2 LAST SEC 1
J 0
(-6800 4375);
DISPLAY 0.680851 (-6800 4375);
PAINT MONO (-6800 4375);
DISPLAY INVISIBLE (-6800 4375);
FORCEPROP 2 LAST SEC_TYPE 0805
J 0
(-6800 4375);
DISPLAY 1.021277 (-6800 4375);
PAINT ORANGE (-6800 4375);
DISPLAY INVISIBLE (-6800 4375);
FORCEPROP 2 LAST ROOM PVCCIN_CPU0_PWR_VR
J 0
(-6800 4325);
DISPLAY 1.361702 (-6800 4325);
PAINT ORANGE (-6800 4325);
DISPLAY INVISIBLE (-6800 4325);
FORCEPROP 1 LAST PATH I1
J 0
(-6800 4325);
DISPLAY 0.978723 (-6800 4325);
PAINT WHITE (-6800 4325);
DISPLAY INVISIBLE (-6800 4325);
FORCEPROP 2 LAST CDS_LIB mstr_discrete
J 0
(-6850 4175);
PAINT ORANGE (-6850 4175);
DISPLAY INVISIBLE (-6850 4175);
FORCEADD GND..1
(-2200 3750);
FORCEPROP 3 LASTPIN (-2200 3800) SIG_NAME GND\g
J 0
(-2190 3810);
DISPLAY 0.659574 (-2190 3810);
PAINT MONO (-2190 3810);
DISPLAY INVISIBLE (-2190 3810);
FORCEPROP 1 LAST HDL_POWER GND
J 0
(-2200 3900);
DISPLAY 1.170213 (-2200 3900);
PAINT GREEN (-2200 3900);
DISPLAY INVISIBLE (-2200 3900);
FORCEPROP 1 LAST BODY_TYPE PLUMBING
J 0
(-2245 3707);
DISPLAY 0.340426 (-2245 3707);
PAINT GREEN (-2245 3707);
DISPLAY INVISIBLE (-2245 3707);
FORCEPROP 2 LAST CDS_LIB mstr_symbols
J 0
(-2200 3750);
PAINT MONO (-2200 3750);
DISPLAY INVISIBLE (-2200 3750);
FORCEPROP 1 LAST PATH I100
J 0
(-2125 3750);
DISPLAY 0.872340 (-2125 3750);
PAINT AQUA (-2125 3750);
DISPLAY INVISIBLE (-2125 3750);
FORCEPROP 1 LAST SIZE 1B
J 0
(-2125 3700);
DISPLAY 1.170213 (-2125 3700);
PAINT AQUA (-2125 3700);
DISPLAY INVISIBLE (-2125 3700);
FORCEPROP 1 LAST VOLTAGE 0
J 0
(-2200 3750);
PAINT SKYBLUE (-2200 3750);
DISPLAY INVISIBLE (-2200 3750);
FORCEPROP 2 LAST ROOM VDDQ_KLM_PWR_VR
J 0
(-2775 3825);
DISPLAY 1.361702 (-2775 3825);
PAINT ORANGE (-2775 3825);
DISPLAY INVISIBLE (-2775 3825);
FORCEADD SC2K2P50V3KX-GP..1
(-2100 3475);
FORCEPROP 1 LAST VALUE SC2K2P50V3KX-GP
J 0
(-2075 3425);
DISPLAY 0.617021 (-2075 3425);
PAINT GREEN (-2075 3425);
FORCEPROP 1 LAST LOCATION CT38
J 0
(-2075 3505);
DISPLAY 0.617021 (-2075 3505);
PAINT GREEN (-2075 3505);
FORCEPROP 0 LAST STATUS NOPOP
J 0
(-2375 3475);
DISPLAY 1.021277 (-2375 3475);
PAINT ORANGE (-2375 3475);
FORCEPROP 2 LAST CDS_LIB w_hdl
J 0
(-2100 3475);
PAINT MONO (-2100 3475);
DISPLAY INVISIBLE (-2100 3475);
FORCEPROP 1 LAST PATH I101
J 0
(-2100 3475);
DISPLAY 0.617021 (-2100 3475);
PAINT GREEN (-2100 3475);
DISPLAY INVISIBLE (-2100 3475);
FORCEPROP 1 LAST CDS_LMAN_SYM_OUTLINE -50,25,50,-25
J 0
(-2100 3475);
DISPLAY 0.468085 (-2100 3475);
PAINT GREEN (-2100 3475);
DISPLAY INVISIBLE (-2100 3475);
FORCEPROP 1 LAST PART_NUMBER 78.22224.2BL
J 0
(-2100 3475);
DISPLAY 0.617021 (-2100 3475);
PAINT GREEN (-2100 3475);
DISPLAY INVISIBLE (-2100 3475);
FORCEPROP 1 LAST PACK_TYPE SMD-BCG6
J 0
(-2100 3475);
DISPLAY 0.617021 (-2100 3475);
PAINT GREEN (-2100 3475);
DISPLAY INVISIBLE (-2100 3475);
FORCEADD 3D01R5F-GP..1
R 4
(-2100 3200);
FORCEPROP 0 LAST STATUS NOPOP
J 0
(-2375 3225);
DISPLAY 1.021277 (-2375 3225);
PAINT ORANGE (-2375 3225);
FORCEPROP 1 LAST VALUE 3D01R5F-GP
J 0
(-2350 3125);
DISPLAY 0.617021 (-2350 3125);
PAINT GREEN (-2350 3125);
FORCEPROP 1 LAST LOCATION RT26
J 0
(-2225 3170);
DISPLAY 0.617021 (-2225 3170);
PAINT GREEN (-2225 3170);
FORCEPROP 2 LASTPIN (-2100 3325) SIG_NAME UN$203$3D01R5F-GP$I102$2
J 0
(-2090 3335);
DISPLAY 0.659574 (-2090 3335);
PAINT MONO (-2090 3335);
DISPLAY INVISIBLE (-2090 3335);
FORCEPROP 1 LAST PACK_TYPE SMD-RG5
R 2
J 0
(-2100 3200);
DISPLAY 0.617021 (-2100 3200);
PAINT GREEN (-2100 3200);
DISPLAY INVISIBLE (-2100 3200);
FORCEPROP 1 LAST PART_NUMBER 64.3R015.16L
R 2
J 0
(-2100 3200);
DISPLAY 0.617021 (-2100 3200);
PAINT GREEN (-2100 3200);
DISPLAY INVISIBLE (-2100 3200);
FORCEPROP 2 LAST CDS_LIB w_hdl
J 0
(-2100 3200);
PAINT MONO (-2100 3200);
DISPLAY INVISIBLE (-2100 3200);
FORCEPROP 1 LAST PATH I102
R 2
J 0
(-2100 3200);
DISPLAY 0.617021 (-2100 3200);
PAINT GREEN (-2100 3200);
DISPLAY INVISIBLE (-2100 3200);
FORCEPROP 1 LAST CDS_LMAN_SYM_OUTLINE -50,75,50,-75
R 2
J 0
(-2100 3200);
DISPLAY 0.468085 (-2100 3200);
PAINT GREEN (-2100 3200);
DISPLAY INVISIBLE (-2100 3200);
FORCEADD GND..1
(-2100 2975);
FORCEPROP 3 LASTPIN (-2100 3025) SIG_NAME GND\g
J 0
(-2090 3035);
DISPLAY 0.659574 (-2090 3035);
PAINT MONO (-2090 3035);
DISPLAY INVISIBLE (-2090 3035);
FORCEPROP 1 LAST HDL_POWER GND
J 0
(-2100 3125);
DISPLAY 1.723404 (-2100 3125);
PAINT GREEN (-2100 3125);
DISPLAY INVISIBLE (-2100 3125);
FORCEPROP 1 LAST BODY_TYPE PLUMBING
J 0
(-2145 2932);
DISPLAY 0.340426 (-2145 2932);
PAINT GREEN (-2145 2932);
DISPLAY INVISIBLE (-2145 2932);
FORCEPROP 1 LAST SIZE 1B
J 0
(-2025 2925);
DISPLAY 1.723404 (-2025 2925);
PAINT GREEN (-2025 2925);
DISPLAY INVISIBLE (-2025 2925);
FORCEPROP 1 LAST VOLTAGE 0
J 0
(-2100 2975);
PAINT SKYBLUE (-2100 2975);
DISPLAY INVISIBLE (-2100 2975);
FORCEPROP 2 LAST BOM_COST PROC_VRD_VCCIN_CPU0
J 0
(-2475 3050);
DISPLAY 1.446809 (-2475 3050);
PAINT MONO (-2475 3050);
DISPLAY INVISIBLE (-2475 3050);
FORCEPROP 2 LAST ROOM PVCCIN_CPU0_PWR_VR
J 0
(-2650 3050);
DISPLAY 1.936170 (-2650 3050);
PAINT ORANGE (-2650 3050);
DISPLAY INVISIBLE (-2650 3050);
FORCEPROP 1 LAST PATH I103
J 0
(-2025 2975);
DISPLAY 0.872340 (-2025 2975);
PAINT AQUA (-2025 2975);
DISPLAY INVISIBLE (-2025 2975);
FORCEPROP 2 LAST CDS_LIB mstr_symbols
J 0
(-2100 2975);
PAINT MONO (-2100 2975);
DISPLAY INVISIBLE (-2100 2975);
FORCEADD GND..1
(-2100 375);
FORCEPROP 3 LASTPIN (-2100 425) SIG_NAME GND\g
J 0
(-2090 435);
DISPLAY 0.659574 (-2090 435);
PAINT MONO (-2090 435);
DISPLAY INVISIBLE (-2090 435);
FORCEPROP 2 LAST CDS_LIB mstr_symbols
J 0
(-2100 375);
PAINT MONO (-2100 375);
DISPLAY INVISIBLE (-2100 375);
FORCEPROP 1 LAST PATH I104
J 0
(-2025 375);
DISPLAY 0.872340 (-2025 375);
PAINT AQUA (-2025 375);
DISPLAY INVISIBLE (-2025 375);
FORCEPROP 1 LAST SIZE 1B
J 0
(-2025 325);
DISPLAY 1.723404 (-2025 325);
PAINT GREEN (-2025 325);
DISPLAY INVISIBLE (-2025 325);
FORCEPROP 1 LAST VOLTAGE 0
J 0
(-2100 375);
PAINT SKYBLUE (-2100 375);
DISPLAY INVISIBLE (-2100 375);
FORCEPROP 2 LAST BOM_COST PROC_VRD_VCCIN_CPU0
J 0
(-2475 450);
DISPLAY 1.446809 (-2475 450);
PAINT MONO (-2475 450);
DISPLAY INVISIBLE (-2475 450);
FORCEPROP 2 LAST ROOM PVCCIN_CPU0_PWR_VR
J 0
(-2650 450);
DISPLAY 1.936170 (-2650 450);
PAINT ORANGE (-2650 450);
DISPLAY INVISIBLE (-2650 450);
FORCEPROP 1 LAST BODY_TYPE PLUMBING
J 0
(-2145 332);
DISPLAY 0.340426 (-2145 332);
PAINT GREEN (-2145 332);
DISPLAY INVISIBLE (-2145 332);
FORCEPROP 1 LAST HDL_POWER GND
J 0
(-2100 525);
DISPLAY 1.723404 (-2100 525);
PAINT GREEN (-2100 525);
DISPLAY INVISIBLE (-2100 525);
FORCEADD 3D01R5F-GP..1
R 4
(-2100 575);
FORCEPROP 1 LAST LOCATION RT27
J 0
(-2225 545);
DISPLAY 0.617021 (-2225 545);
PAINT GREEN (-2225 545);
FORCEPROP 1 LAST VALUE 3D01R5F-GP
J 0
(-2325 500);
DISPLAY 0.617021 (-2325 500);
PAINT GREEN (-2325 500);
FORCEPROP 0 LAST STATUS NOPOP
J 0
(-2325 600);
DISPLAY 1.021277 (-2325 600);
PAINT ORANGE (-2325 600);
FORCEPROP 1 LAST CDS_LMAN_SYM_OUTLINE -50,75,50,-75
R 2
J 0
(-2100 575);
DISPLAY 0.468085 (-2100 575);
PAINT GREEN (-2100 575);
DISPLAY INVISIBLE (-2100 575);
FORCEPROP 1 LAST PATH I105
R 2
J 0
(-2100 575);
DISPLAY 0.617021 (-2100 575);
PAINT GREEN (-2100 575);
DISPLAY INVISIBLE (-2100 575);
FORCEPROP 2 LAST CDS_LIB w_hdl
J 0
(-2100 575);
PAINT MONO (-2100 575);
DISPLAY INVISIBLE (-2100 575);
FORCEPROP 1 LAST PART_NUMBER 64.3R015.16L
R 2
J 0
(-2100 575);
DISPLAY 0.617021 (-2100 575);
PAINT GREEN (-2100 575);
DISPLAY INVISIBLE (-2100 575);
FORCEPROP 1 LAST PACK_TYPE SMD-RG5
R 2
J 0
(-2100 575);
DISPLAY 0.617021 (-2100 575);
PAINT GREEN (-2100 575);
DISPLAY INVISIBLE (-2100 575);
FORCEPROP 2 LASTPIN (-2100 700) SIG_NAME UN$203$3D01R5F-GP$I105$2
J 0
(-2090 710);
DISPLAY 0.659574 (-2090 710);
PAINT MONO (-2090 710);
DISPLAY INVISIBLE (-2090 710);
FORCEADD SC2K2P50V3KX-GP..1
(-2100 800);
FORCEPROP 1 LAST LOCATION CT41
J 0
(-2075 830);
DISPLAY 0.617021 (-2075 830);
PAINT GREEN (-2075 830);
FORCEPROP 1 LAST VALUE SC2K2P50V3KX-GP
J 0
(-2075 750);
DISPLAY 0.617021 (-2075 750);
PAINT GREEN (-2075 750);
FORCEPROP 0 LAST STATUS NOPOP
J 0
(-2325 725);
DISPLAY 1.021277 (-2325 725);
PAINT ORANGE (-2325 725);
FORCEPROP 1 LAST PART_NUMBER 78.22224.2BL
J 0
(-2100 800);
DISPLAY 0.617021 (-2100 800);
PAINT GREEN (-2100 800);
DISPLAY INVISIBLE (-2100 800);
FORCEPROP 1 LAST PACK_TYPE SMD-BCG6
J 0
(-2100 800);
DISPLAY 0.617021 (-2100 800);
PAINT GREEN (-2100 800);
DISPLAY INVISIBLE (-2100 800);
FORCEPROP 1 LAST CDS_LMAN_SYM_OUTLINE -50,25,50,-25
J 0
(-2100 800);
DISPLAY 0.468085 (-2100 800);
PAINT GREEN (-2100 800);
DISPLAY INVISIBLE (-2100 800);
FORCEPROP 1 LAST PATH I106
J 0
(-2100 800);
DISPLAY 0.617021 (-2100 800);
PAINT GREEN (-2100 800);
DISPLAY INVISIBLE (-2100 800);
FORCEPROP 2 LAST CDS_LIB w_hdl
J 0
(-2100 800);
PAINT MONO (-2100 800);
DISPLAY INVISIBLE (-2100 800);
FORCEADD GND..1
(-2150 1050);
FORCEPROP 3 LASTPIN (-2150 1100) SIG_NAME GND\g
J 0
(-2140 1110);
DISPLAY 0.659574 (-2140 1110);
PAINT MONO (-2140 1110);
DISPLAY INVISIBLE (-2140 1110);
FORCEPROP 1 LAST SIZE 1B
J 0
(-2075 1000);
DISPLAY 1.170213 (-2075 1000);
PAINT AQUA (-2075 1000);
DISPLAY INVISIBLE (-2075 1000);
FORCEPROP 1 LAST VOLTAGE 0
J 0
(-2150 1050);
PAINT SKYBLUE (-2150 1050);
DISPLAY INVISIBLE (-2150 1050);
FORCEPROP 2 LAST ROOM VDDQ_KLM_PWR_VR
J 0
(-2725 1125);
DISPLAY 1.361702 (-2725 1125);
PAINT ORANGE (-2725 1125);
DISPLAY INVISIBLE (-2725 1125);
FORCEPROP 1 LAST PATH I107
J 0
(-2075 1050);
DISPLAY 0.872340 (-2075 1050);
PAINT AQUA (-2075 1050);
DISPLAY INVISIBLE (-2075 1050);
FORCEPROP 2 LAST CDS_LIB mstr_symbols
J 0
(-2150 1050);
PAINT MONO (-2150 1050);
DISPLAY INVISIBLE (-2150 1050);
FORCEPROP 1 LAST BODY_TYPE PLUMBING
J 0
(-2195 1007);
DISPLAY 0.340426 (-2195 1007);
PAINT GREEN (-2195 1007);
DISPLAY INVISIBLE (-2195 1007);
FORCEPROP 1 LAST HDL_POWER GND
J 0
(-2150 1200);
DISPLAY 1.170213 (-2150 1200);
PAINT GREEN (-2150 1200);
DISPLAY INVISIBLE (-2150 1200);
FORCEADD CAP..1
(-2150 1250);
FORCEPROP 1 LAST VALUE 1000PF
J 0
(-2100 1300);
DISPLAY 0.617021 (-2100 1300);
PAINT SKYBLUE (-2100 1300);
FORCEPROP 1 LAST LOCATION CT42
J 0
(-2300 1250);
DISPLAY 0.617021 (-2300 1250);
PAINT AQUA (-2300 1250);
FORCEPROP 0 LAST STATUS NOPOP
J 0
(-2400 1300);
DISPLAY 1.021277 (-2400 1300);
PAINT ORANGE (-2400 1300);
FORCEPROP 1 LAST PACK_TYPE 0402LF
J 0
(-2100 1050);
DISPLAY 0.617021 (-2100 1050);
PAINT SKYBLUE (-2100 1050);
FORCEPROP 1 LAST PART_NUMBER A36096-046
J 0
(-2100 1100);
DISPLAY 0.617021 (-2100 1100);
PAINT BLUE (-2100 1100);
FORCEPROP 1 LAST MATERIAL X7R
J 0
(-2100 1150);
DISPLAY 0.617021 (-2100 1150);
PAINT SKYBLUE (-2100 1150);
FORCEPROP 1 LAST TOLERANCE 10%
J 0
(-2100 1200);
DISPLAY 0.617021 (-2100 1200);
PAINT SKYBLUE (-2100 1200);
FORCEPROP 1 LAST VOLTAGE 50V
J 0
(-2100 1250);
DISPLAY 0.617021 (-2100 1250);
PAINT SKYBLUE (-2100 1250);
FORCEPROP 2 LAST CDS_LIB mstr_discrete
J 0
(-2150 1250);
PAINT MONO (-2150 1250);
DISPLAY INVISIBLE (-2150 1250);
FORCEPROP 1 LAST PATH I108
J 0
(-2100 1400);
DISPLAY 0.978723 (-2100 1400);
PAINT WHITE (-2100 1400);
DISPLAY INVISIBLE (-2100 1400);
FORCEPROP 0 LAST ROOM VDDQ_KLM_PWR_VR
J 0
(-2100 1450);
DISPLAY 1.021277 (-2100 1450);
PAINT ORANGE (-2100 1450);
DISPLAY INVISIBLE (-2100 1450);
FORCEPROP 1 LASTPIN (-2150 1150) $PN 2
J 0
(-2140 1130);
DISPLAY 0.787234 (-2140 1130);
PAINT ORANGE (-2140 1130);
DISPLAY INVISIBLE (-2140 1130);
FORCEPROP 1 LASTPIN (-2150 1350) $PN 1
J 0
(-2140 1330);
DISPLAY 0.787234 (-2140 1330);
PAINT ORANGE (-2140 1330);
DISPLAY INVISIBLE (-2140 1330);
FORCEADD PVCCIN_CPU0..1
(-750 1050);
FORCEPROP 3 LASTPIN (-750 1000) SIG_NAME PVCCIN_CPU0\g
J 0
(-740 1010);
DISPLAY 0.659574 (-740 1010);
PAINT MONO (-740 1010);
DISPLAY INVISIBLE (-740 1010);
FORCEPROP 1 LAST HDL_POWER PVCCIN_CPU0
J 1
(-750 1100);
DISPLAY 0.872340 (-750 1100);
PAINT GREEN (-750 1100);
DISPLAY INVISIBLE (-750 1100);
FORCEPROP 1 LAST BODY_TYPE PLUMBING
J 0
(-795 1007);
DISPLAY 0.340426 (-795 1007);
PAINT GREEN (-795 1007);
DISPLAY INVISIBLE (-795 1007);
FORCEPROP 1 LAST VOLTAGE 2.0V
J 0
(-795 1007);
DISPLAY 0.340426 (-795 1007);
PAINT SKYBLUE (-795 1007);
DISPLAY INVISIBLE (-795 1007);
FORCEPROP 2 LAST CDS_LIB mstr_symbols
J 0
(-750 1050);
PAINT ORANGE (-750 1050);
DISPLAY INVISIBLE (-750 1050);
FORCEPROP 1 LAST PATH I109
J 0
(-700 1075);
DISPLAY 0.872340 (-700 1075);
PAINT AQUA (-700 1075);
DISPLAY INVISIBLE (-700 1075);
FORCEADD RES..1
(-4950 3700);
FORCEPROP 1 LAST PACK_TYPE 0402
J 0
(-4850 3550);
DISPLAY 0.617021 (-4850 3550);
PAINT SKYBLUE (-4850 3550);
FORCEPROP 1 LAST LOCATION RT25
J 0
(-5000 3725);
DISPLAY 0.617021 (-5000 3725);
PAINT AQUA (-5000 3725);
FORCEPROP 1 LAST PART_NUMBER G21497-005
J 0
(-5050 3650);
DISPLAY 0.617021 (-5050 3650);
PAINT BLUE (-5050 3650);
FORCEPROP 1 LAST TOLERANCE 5%
J 0
(-4950 3600);
DISPLAY 0.617021 (-4950 3600);
PAINT SKYBLUE (-4950 3600);
FORCEPROP 1 LAST VALUE 0.0
J 2
(-4975 3600);
DISPLAY 0.617021 (-4975 3600);
PAINT SKYBLUE (-4975 3600);
FORCEPROP 1 LAST WATTAGE 1/16W
J 2
(-4975 3550);
DISPLAY 0.617021 (-4975 3550);
PAINT SKYBLUE (-4975 3550);
FORCEPROP 1 LAST MATERIAL CHIP
J 0
(-4950 3550);
DISPLAY 0.617021 (-4950 3550);
PAINT SKYBLUE (-4950 3550);
FORCEPROP 2 LAST ROOM BMC_DEBUG_HEADER
J 0
(-5000 3850);
DISPLAY 1.021277 (-5000 3850);
PAINT ORANGE (-5000 3850);
DISPLAY INVISIBLE (-5000 3850);
FORCEPROP 2 LAST BOM_COST DEBUG
J 0
(-5000 3900);
DISPLAY 1.021277 (-5000 3900);
PAINT ORANGE (-5000 3900);
DISPLAY INVISIBLE (-5000 3900);
FORCEPROP 1 LAST PATH I110
J 0
(-5000 3850);
DISPLAY 0.978723 (-5000 3850);
PAINT WHITE (-5000 3850);
DISPLAY INVISIBLE (-5000 3850);
FORCEPROP 2 LAST CDS_LIB mstr_discrete
J 0
(-4950 3700);
PAINT MONO (-4950 3700);
DISPLAY INVISIBLE (-4950 3700);
FORCEPROP 1 LASTPIN (-5050 3700) $PN 1
J 0
(-5038 3712);
DISPLAY 0.787234 (-5038 3712);
PAINT ORANGE (-5038 3712);
DISPLAY INVISIBLE (-5038 3712);
FORCEPROP 1 LASTPIN (-4850 3700) $PN 2
J 0
(-4888 3712);
DISPLAY 0.787234 (-4888 3712);
PAINT ORANGE (-4888 3712);
DISPLAY INVISIBLE (-4888 3712);
FORCEADD RES..1
(-5175 950);
FORCEPROP 1 LAST WATTAGE 1/16W
J 2
(-5200 800);
DISPLAY 0.617021 (-5200 800);
PAINT SKYBLUE (-5200 800);
FORCEPROP 1 LAST VALUE 0.0
J 2
(-5200 850);
DISPLAY 0.617021 (-5200 850);
PAINT SKYBLUE (-5200 850);
FORCEPROP 1 LAST PART_NUMBER G21497-005
J 0
(-5275 900);
DISPLAY 0.617021 (-5275 900);
PAINT BLUE (-5275 900);
FORCEPROP 1 LAST PACK_TYPE 0402
J 0
(-5075 800);
DISPLAY 0.617021 (-5075 800);
PAINT SKYBLUE (-5075 800);
FORCEPROP 1 LAST MATERIAL CHIP
J 0
(-5175 800);
DISPLAY 0.617021 (-5175 800);
PAINT SKYBLUE (-5175 800);
FORCEPROP 1 LAST TOLERANCE 5%
J 0
(-5175 850);
DISPLAY 0.617021 (-5175 850);
PAINT SKYBLUE (-5175 850);
FORCEPROP 1 LAST LOCATION RT28
J 0
(-5225 975);
DISPLAY 0.617021 (-5225 975);
PAINT AQUA (-5225 975);
FORCEPROP 2 LAST CDS_LIB mstr_discrete
J 0
(-5175 950);
PAINT MONO (-5175 950);
DISPLAY INVISIBLE (-5175 950);
FORCEPROP 1 LAST PATH I111
J 0
(-5225 1100);
DISPLAY 0.978723 (-5225 1100);
PAINT WHITE (-5225 1100);
DISPLAY INVISIBLE (-5225 1100);
FORCEPROP 2 LAST BOM_COST DEBUG
J 0
(-5225 1150);
DISPLAY 1.021277 (-5225 1150);
PAINT ORANGE (-5225 1150);
DISPLAY INVISIBLE (-5225 1150);
FORCEPROP 2 LAST ROOM BMC_DEBUG_HEADER
J 0
(-5225 1100);
DISPLAY 1.021277 (-5225 1100);
PAINT ORANGE (-5225 1100);
DISPLAY INVISIBLE (-5225 1100);
FORCEPROP 1 LASTPIN (-5275 950) $PN 1
J 0
(-5263 962);
DISPLAY 0.787234 (-5263 962);
PAINT ORANGE (-5263 962);
DISPLAY INVISIBLE (-5263 962);
FORCEPROP 1 LASTPIN (-5075 950) $PN 2
J 0
(-5113 962);
DISPLAY 0.787234 (-5113 962);
PAINT ORANGE (-5113 962);
DISPLAY INVISIBLE (-5113 962);
FORCEADD PVCCIN_CPU0..1
(-750 3725);
FORCEPROP 3 LASTPIN (-750 3675) SIG_NAME PVCCIN_CPU0\g
J 0
(-740 3685);
DISPLAY 0.659574 (-740 3685);
PAINT MONO (-740 3685);
DISPLAY INVISIBLE (-740 3685);
FORCEPROP 1 LAST HDL_POWER PVCCIN_CPU0
J 1
(-750 3775);
DISPLAY 0.872340 (-750 3775);
PAINT GREEN (-750 3775);
DISPLAY INVISIBLE (-750 3775);
FORCEPROP 1 LAST BODY_TYPE PLUMBING
J 0
(-795 3682);
DISPLAY 0.340426 (-795 3682);
PAINT GREEN (-795 3682);
DISPLAY INVISIBLE (-795 3682);
FORCEPROP 2 LAST CDS_LIB mstr_symbols
J 0
(-750 3725);
PAINT ORANGE (-750 3725);
DISPLAY INVISIBLE (-750 3725);
FORCEPROP 1 LAST PATH I12
J 0
(-700 3750);
DISPLAY 0.872340 (-700 3750);
PAINT AQUA (-700 3750);
DISPLAY INVISIBLE (-700 3750);
FORCEPROP 1 LAST VOLTAGE 2.0V
J 0
(-795 3682);
DISPLAY 0.340426 (-795 3682);
PAINT SKYBLUE (-795 3682);
DISPLAY INVISIBLE (-795 3682);
FORCEADD GND..1
(-1025 3075);
FORCEPROP 3 LASTPIN (-1025 3125) SIG_NAME GND\g
J 0
(-1015 3135);
DISPLAY 0.659574 (-1015 3135);
PAINT MONO (-1015 3135);
DISPLAY INVISIBLE (-1015 3135);
FORCEPROP 1 LAST HDL_POWER GND
J 0
(-1025 3225);
DISPLAY 1.723404 (-1025 3225);
PAINT GREEN (-1025 3225);
DISPLAY INVISIBLE (-1025 3225);
FORCEPROP 1 LAST BODY_TYPE PLUMBING
J 0
(-1070 3032);
DISPLAY 0.340426 (-1070 3032);
PAINT GREEN (-1070 3032);
DISPLAY INVISIBLE (-1070 3032);
FORCEPROP 1 LAST PATH I14
J 0
(-950 3075);
DISPLAY 0.872340 (-950 3075);
PAINT AQUA (-950 3075);
DISPLAY INVISIBLE (-950 3075);
FORCEPROP 1 LAST SIZE 1B
J 0
(-950 3025);
DISPLAY 1.723404 (-950 3025);
PAINT GREEN (-950 3025);
DISPLAY INVISIBLE (-950 3025);
FORCEPROP 1 LAST VOLTAGE 0
J 0
(-1025 3075);
PAINT SKYBLUE (-1025 3075);
DISPLAY INVISIBLE (-1025 3075);
FORCEPROP 2 LAST CDS_LIB mstr_symbols
J 0
(-1025 3075);
DISPLAY 1.936170 (-1025 3075);
PAINT ORANGE (-1025 3075);
DISPLAY INVISIBLE (-1025 3075);
FORCEPROP 2 LAST BOM_COST PROC_VRD_VCCIN_CPU0
J 0
(-1400 3150);
DISPLAY 1.446809 (-1400 3150);
PAINT MONO (-1400 3150);
DISPLAY INVISIBLE (-1400 3150);
FORCEPROP 2 LAST ROOM PVCCIN_CPU0_PWR_VR
J 0
(-1575 3150);
DISPLAY 1.936170 (-1575 3150);
PAINT ORANGE (-1575 3150);
DISPLAY INVISIBLE (-1575 3150);
FORCEADD INDUCTOR..1
(-1550 3625);
FORCEPROP 1 LAST PART_NUMBER D92183-034
J 0
(-1675 3575);
DISPLAY 0.617021 (-1675 3575);
PAINT BLUE (-1675 3575);
FORCEPROP 1 LAST MATERIAL IND
J 0
(-1510 3515);
DISPLAY 0.617021 (-1510 3515);
PAINT SKYBLUE (-1510 3515);
FORCEPROP 1 LAST VALUE 0.12UH
J 2
(-1555 3515);
DISPLAY 0.617021 (-1555 3515);
PAINT SKYBLUE (-1555 3515);
FORCEPROP 1 LAST LOCATION L4D2
J 0
(-1650 3675);
DISPLAY 0.617021 (-1650 3675);
PAINT AQUA (-1650 3675);
FORCEPROP 1 LAST PACK_TYPE SM
J 0
(-1385 3515);
DISPLAY 0.617021 (-1385 3515);
PAINT SKYBLUE (-1385 3515);
FORCEPROP 1 LASTPIN (-1450 3625) $PN 2
J 2
(-1440 3635);
DISPLAY 0.617021 (-1440 3635);
PAINT WHITE (-1440 3635);
FORCEPROP 1 LASTPIN (-1650 3625) $PN 1
J 0
(-1650 3635);
DISPLAY 0.617021 (-1650 3635);
PAINT WHITE (-1650 3635);
FORCEPROP 2 LAST CDS_SEC 1
J 0
(-1650 3825);
PAINT MONO (-1650 3825);
DISPLAY INVISIBLE (-1650 3825);
FORCEPROP 2 LAST $SEC 1
J 0
(-1650 3825);
PAINT MONO (-1650 3825);
DISPLAY INVISIBLE (-1650 3825);
FORCEPROP 2 LAST CDS_LIB mstr_discrete
J 0
(-1550 3625);
PAINT ORANGE (-1550 3625);
DISPLAY INVISIBLE (-1550 3625);
FORCEPROP 2 LAST CDS_LOCATION L4D2
J 0
(-1650 3675);
DISPLAY 0.617021 (-1650 3675);
PAINT AQUA (-1650 3675);
DISPLAY INVISIBLE (-1650 3675);
FORCEPROP 1 LAST PATH I15
J 0
(-1650 3775);
DISPLAY 0.978723 (-1650 3775);
PAINT ORANGE (-1650 3775);
DISPLAY INVISIBLE (-1650 3775);
FORCEPROP 2 LAST ROOM PVCCIN_CPU0_PWR_VR
J 0
(-1650 3725);
DISPLAY 1.361702 (-1650 3725);
PAINT ORANGE (-1650 3725);
DISPLAY INVISIBLE (-1650 3725);
FORCEADD CAPP..1
(-1150 2575);
FORCEPROP 1 LAST LOCATION C6R3
J 0
(-1100 2675);
DISPLAY 0.617021 (-1100 2675);
PAINT AQUA (-1100 2675);
FORCEPROP 1 LAST PART_NUMBER 699013-049
J 0
(-1100 2375);
DISPLAY 0.617021 (-1100 2375);
PAINT BLUE (-1100 2375);
FORCEPROP 1 LAST VALUE 470UF
J 0
(-1100 2625);
DISPLAY 0.617021 (-1100 2625);
PAINT SKYBLUE (-1100 2625);
FORCEPROP 1 LAST TOLERANCE 20%
J 0
(-1100 2575);
DISPLAY 0.617021 (-1100 2575);
PAINT SKYBLUE (-1100 2575);
FORCEPROP 1 LASTPIN (-1150 2675) $PN 1
J 0
(-1140 2660);
DISPLAY 0.617021 (-1140 2660);
PAINT GREEN (-1140 2660);
FORCEPROP 1 LASTPIN (-1150 2475) $PN 2
J 0
(-1140 2460);
DISPLAY 0.617021 (-1140 2460);
PAINT GREEN (-1140 2460);
FORCEPROP 1 LAST MATERIAL ALUM
J 0
(-1100 2475);
DISPLAY 0.617021 (-1100 2475);
PAINT SKYBLUE (-1100 2475);
FORCEPROP 1 LAST PACK_TYPE 3018
J 0
(-1100 2425);
DISPLAY 0.617021 (-1100 2425);
PAINT SKYBLUE (-1100 2425);
FORCEPROP 2 LAST SEC_TYPE 3018
J 0
(-1085 2785);
DISPLAY 1.021277 (-1085 2785);
PAINT ORANGE (-1085 2785);
DISPLAY INVISIBLE (-1085 2785);
FORCEPROP 2 LAST SEC 1
J 0
(-1100 2775);
PAINT MONO (-1100 2775);
DISPLAY INVISIBLE (-1100 2775);
FORCEPROP 2 LAST ROOM PVCCIN_CPU0_DECAP_VR
J 0
(-1100 2700);
PAINT MONO (-1100 2700);
DISPLAY INVISIBLE (-1100 2700);
FORCEPROP 1 LAST PATH I16
J 0
(-1100 2725);
DISPLAY 0.978723 (-1100 2725);
PAINT ORANGE (-1100 2725);
DISPLAY INVISIBLE (-1100 2725);
FORCEPROP 2 LAST BOM_COST PROC_VRD_VCCIN_CPU0
J 0
(-1100 2725);
PAINT MONO (-1100 2725);
DISPLAY INVISIBLE (-1100 2725);
FORCEPROP 2 LAST CDS_LOCATION C6R3
J 0
(-1100 2675);
DISPLAY 0.617021 (-1100 2675);
PAINT AQUA (-1100 2675);
DISPLAY INVISIBLE (-1100 2675);
FORCEPROP 2 LAST CDS_LIB mstr_discrete
J 0
(-1150 2575);
PAINT MONO (-1150 2575);
DISPLAY INVISIBLE (-1150 2575);
FORCEPROP 1 LAST VOLTAGE 2.5V
J 0
(-1100 2525);
PAINT SKYBLUE (-1100 2525);
DISPLAY INVISIBLE (-1100 2525);
FORCEADD GND..1
(-700 2200);
FORCEPROP 3 LASTPIN (-700 2250) SIG_NAME GND\g
J 0
(-690 2260);
DISPLAY 0.659574 (-690 2260);
PAINT MONO (-690 2260);
DISPLAY INVISIBLE (-690 2260);
FORCEPROP 1 LAST HDL_POWER GND
J 0
(-700 2350);
DISPLAY 0.893617 (-700 2350);
PAINT GREEN (-700 2350);
DISPLAY INVISIBLE (-700 2350);
FORCEPROP 1 LAST BODY_TYPE PLUMBING
J 0
(-745 2157);
DISPLAY 0.340426 (-745 2157);
PAINT GREEN (-745 2157);
DISPLAY INVISIBLE (-745 2157);
FORCEPROP 1 LAST VOLTAGE 0
J 0
(-700 2200);
PAINT SKYBLUE (-700 2200);
DISPLAY INVISIBLE (-700 2200);
FORCEPROP 2 LAST CDS_LIB mstr_symbols
J 1
(-700 2200);
PAINT ORANGE (-700 2200);
DISPLAY INVISIBLE (-700 2200);
FORCEPROP 1 LAST SIZE 1B
J 0
(-625 2150);
DISPLAY 0.893617 (-625 2150);
PAINT GREEN (-625 2150);
DISPLAY INVISIBLE (-625 2150);
FORCEPROP 1 LAST PATH I17
J 0
(-625 2200);
DISPLAY 0.872340 (-625 2200);
PAINT AQUA (-625 2200);
DISPLAY INVISIBLE (-625 2200);
FORCEPROP 2 LAST BOM_COST PROC_VRD_VCCIN_CPU0
J 0
(-1075 2275);
PAINT MONO (-1075 2275);
DISPLAY INVISIBLE (-1075 2275);
FORCEPROP 2 LAST ROOM PVCCIN_CPU0_DECAP_VR
J 0
(-1250 2275);
PAINT ORANGE (-1250 2275);
DISPLAY INVISIBLE (-1250 2275);
FORCEADD CAPP..1
(-1625 2575);
FORCEPROP 1 LAST LOCATION C6R9
J 0
(-1575 2675);
DISPLAY 0.617021 (-1575 2675);
PAINT AQUA (-1575 2675);
FORCEPROP 1 LAST PART_NUMBER 699013-049
J 0
(-1575 2375);
DISPLAY 0.617021 (-1575 2375);
PAINT BLUE (-1575 2375);
FORCEPROP 1 LAST TOLERANCE 20%
J 0
(-1575 2575);
DISPLAY 0.617021 (-1575 2575);
PAINT SKYBLUE (-1575 2575);
FORCEPROP 1 LAST PACK_TYPE 3018
J 0
(-1575 2425);
DISPLAY 0.617021 (-1575 2425);
PAINT SKYBLUE (-1575 2425);
FORCEPROP 1 LAST MATERIAL ALUM
J 0
(-1575 2475);
DISPLAY 0.617021 (-1575 2475);
PAINT SKYBLUE (-1575 2475);
FORCEPROP 1 LASTPIN (-1625 2675) $PN 1
J 0
(-1615 2660);
DISPLAY 0.617021 (-1615 2660);
PAINT GREEN (-1615 2660);
FORCEPROP 1 LASTPIN (-1625 2475) $PN 2
J 0
(-1615 2460);
DISPLAY 0.617021 (-1615 2460);
PAINT GREEN (-1615 2460);
FORCEPROP 1 LAST VALUE 470UF
J 0
(-1575 2625);
DISPLAY 0.617021 (-1575 2625);
PAINT SKYBLUE (-1575 2625);
FORCEPROP 2 LAST SEC_TYPE 3018
J 0
(-1560 2785);
DISPLAY 1.021277 (-1560 2785);
PAINT ORANGE (-1560 2785);
DISPLAY INVISIBLE (-1560 2785);
FORCEPROP 2 LAST SEC 1
J 0
(-1575 2775);
PAINT MONO (-1575 2775);
DISPLAY INVISIBLE (-1575 2775);
FORCEPROP 2 LAST BOM_COST PROC_VRD_VCCIN_CPU0
J 0
(-1575 2725);
PAINT MONO (-1575 2725);
DISPLAY INVISIBLE (-1575 2725);
FORCEPROP 1 LAST PATH I18
J 0
(-1575 2725);
DISPLAY 0.978723 (-1575 2725);
PAINT ORANGE (-1575 2725);
DISPLAY INVISIBLE (-1575 2725);
FORCEPROP 2 LAST ROOM PVCCIN_CPU0_DECAP_VR
J 0
(-1575 2700);
PAINT MONO (-1575 2700);
DISPLAY INVISIBLE (-1575 2700);
FORCEPROP 2 LAST CDS_LOCATION C6R9
J 0
(-1575 2675);
DISPLAY 0.617021 (-1575 2675);
PAINT AQUA (-1575 2675);
DISPLAY INVISIBLE (-1575 2675);
FORCEPROP 2 LAST CDS_LIB mstr_discrete
J 0
(-1625 2575);
PAINT MONO (-1625 2575);
DISPLAY INVISIBLE (-1625 2575);
FORCEPROP 1 LAST VOLTAGE 2.5V
J 0
(-1575 2525);
PAINT SKYBLUE (-1575 2525);
DISPLAY INVISIBLE (-1575 2525);
FORCEADD OFFPAGE..2
(-1200 2050);
FORCEPROP 2 LAST $XR0 201 
J 0
(-1011 2050);
DISPLAY 0.638298 (-1011 2050);
PAINT MONO (-1011 2050);
FORCEPROP 1 LAST COMMENT_BODY TRUE
J 0
(-1245 1955);
DISPLAY 1.723404 (-1245 1955);
PAINT GREEN (-1245 1955);
DISPLAY INVISIBLE (-1245 1955);
FORCEPROP 1 LAST OFFPAGE TRUE
J 0
(-875 1925);
DISPLAY 1.723404 (-875 1925);
PAINT GREEN (-875 1925);
DISPLAY INVISIBLE (-875 1925);
FORCEPROP 2 LAST BOM_COST PROC_VRD_VCCIN_CPU0
J 0
(-1000 2100);
DISPLAY 1.446809 (-1000 2100);
PAINT MONO (-1000 2100);
DISPLAY INVISIBLE (-1000 2100);
FORCEPROP 2 LAST CDS_LIB mstr_standard
J 0
(-1200 2050);
PAINT ORANGE (-1200 2050);
DISPLAY INVISIBLE (-1200 2050);
FORCEPROP 2 LAST PATH I19
J 0
(-1025 2125);
DISPLAY 1.021277 (-1025 2125);
PAINT ORANGE (-1025 2125);
DISPLAY INVISIBLE (-1025 2125);
FORCEPROP 2 LAST ROOM PVCCIN_CPU0_PWR_VR
J 0
(-1600 2125);
DISPLAY 1.936170 (-1600 2125);
PAINT ORANGE (-1600 2125);
DISPLAY INVISIBLE (-1600 2125);
FORCEADD CAP..1
(-7125 4150);
FORCEPROP 1 LAST TOLERANCE 10%
J 0
(-7075 4100);
DISPLAY 0.617021 (-7075 4100);
PAINT SKYBLUE (-7075 4100);
FORCEPROP 1 LAST VALUE 10UF
J 0
(-7075 4200);
DISPLAY 0.617021 (-7075 4200);
PAINT SKYBLUE (-7075 4200);
FORCEPROP 1 LAST LOCATION C6R6
J 0
(-7075 4250);
DISPLAY 0.617021 (-7075 4250);
PAINT AQUA (-7075 4250);
FORCEPROP 1 LAST VOLTAGE 16V
J 0
(-7075 4150);
DISPLAY 0.617021 (-7075 4150);
PAINT SKYBLUE (-7075 4150);
FORCEPROP 1 LASTPIN (-7125 4250) $PN 1
J 0
(-7115 4230);
DISPLAY 0.617021 (-7115 4230);
PAINT ORANGE (-7115 4230);
FORCEPROP 1 LAST PART_NUMBER C95333-007
J 0
(-7075 4000);
DISPLAY 0.617021 (-7075 4000);
PAINT BLUE (-7075 4000);
FORCEPROP 1 LASTPIN (-7125 4050) $PN 2
J 0
(-7115 4030);
DISPLAY 0.617021 (-7115 4030);
PAINT ORANGE (-7115 4030);
FORCEPROP 1 LAST MATERIAL X6S
J 0
(-7075 4050);
DISPLAY 0.617021 (-7075 4050);
PAINT SKYBLUE (-7075 4050);
FORCEPROP 1 LAST PACK_TYPE 0805
J 0
(-7075 3950);
DISPLAY 0.617021 (-7075 3950);
PAINT SKYBLUE (-7075 3950);
FORCEPROP 2 LAST ROOM PVCCIN_CPU0_PWR_VR
J 0
(-7075 4300);
DISPLAY 1.361702 (-7075 4300);
PAINT ORANGE (-7075 4300);
DISPLAY INVISIBLE (-7075 4300);
FORCEPROP 2 LAST SEC 1
J 0
(-7075 4350);
DISPLAY 0.680851 (-7075 4350);
PAINT MONO (-7075 4350);
DISPLAY INVISIBLE (-7075 4350);
FORCEPROP 2 LAST SEC_TYPE 0805
J 0
(-7075 4350);
DISPLAY 1.021277 (-7075 4350);
PAINT ORANGE (-7075 4350);
DISPLAY INVISIBLE (-7075 4350);
FORCEPROP 2 LAST CDS_LIB mstr_discrete
J 0
(-7125 4150);
PAINT ORANGE (-7125 4150);
DISPLAY INVISIBLE (-7125 4150);
FORCEPROP 2 LAST CDS_LOCATION C6R6
J 0
(-7075 4250);
DISPLAY 0.617021 (-7075 4250);
PAINT AQUA (-7075 4250);
DISPLAY INVISIBLE (-7075 4250);
FORCEPROP 1 LAST PATH I2
J 0
(-7075 4300);
DISPLAY 0.978723 (-7075 4300);
PAINT WHITE (-7075 4300);
DISPLAY INVISIBLE (-7075 4300);
FORCEADD OFFPAGE..2
(-1225 1400);
FORCEPROP 2 LAST $XR0 202 
J 0
(-1036 1400);
DISPLAY 0.638298 (-1036 1400);
PAINT MONO (-1036 1400);
FORCEPROP 2 LAST $XR1 203 
J 0
(-916 1400);
DISPLAY 0.638298 (-916 1400);
PAINT MONO (-916 1400);
FORCEPROP 2 LAST $XR2 204 
J 0
(-796 1400);
DISPLAY 0.638298 (-796 1400);
PAINT MONO (-796 1400);
FORCEPROP 2 LAST $XR3 201 
J 0
(-676 1400);
DISPLAY 0.638298 (-676 1400);
PAINT MONO (-676 1400);
FORCEPROP 1 LAST COMMENT_BODY TRUE
J 0
(-1270 1305);
DISPLAY 1.723404 (-1270 1305);
PAINT GREEN (-1270 1305);
DISPLAY INVISIBLE (-1270 1305);
FORCEPROP 1 LAST OFFPAGE TRUE
J 0
(-900 1275);
DISPLAY 1.723404 (-900 1275);
PAINT GREEN (-900 1275);
DISPLAY INVISIBLE (-900 1275);
FORCEPROP 2 LAST ROOM PVCCIN_CPU0_PWR_VR
J 0
(-1625 1475);
DISPLAY 1.936170 (-1625 1475);
PAINT ORANGE (-1625 1475);
DISPLAY INVISIBLE (-1625 1475);
FORCEPROP 2 LAST CDS_LIB mstr_standard
J 0
(-1225 1400);
PAINT ORANGE (-1225 1400);
DISPLAY INVISIBLE (-1225 1400);
FORCEPROP 2 LAST BOM_COST PROC_VRD_VCCIN_CPU0
J 0
(-1025 1450);
DISPLAY 1.446809 (-1025 1450);
PAINT MONO (-1025 1450);
DISPLAY INVISIBLE (-1025 1450);
FORCEPROP 2 LAST PATH I20
J 0
(-1050 1475);
DISPLAY 1.021277 (-1050 1475);
PAINT ORANGE (-1050 1475);
DISPLAY INVISIBLE (-1050 1475);
FORCEADD OFFPAGE..2
(-1125 1725);
FORCEPROP 2 LAST $XR0 201 
J 0
(-936 1725);
DISPLAY 0.638298 (-936 1725);
PAINT MONO (-936 1725);
FORCEPROP 1 LAST COMMENT_BODY TRUE
J 0
(-1170 1630);
DISPLAY 1.723404 (-1170 1630);
PAINT GREEN (-1170 1630);
DISPLAY INVISIBLE (-1170 1630);
FORCEPROP 1 LAST OFFPAGE TRUE
J 0
(-800 1600);
DISPLAY 1.723404 (-800 1600);
PAINT GREEN (-800 1600);
DISPLAY INVISIBLE (-800 1600);
FORCEPROP 2 LAST BOM_COST PROC_VRD_VCCIN_CPU0
J 0
(-925 1775);
DISPLAY 1.446809 (-925 1775);
PAINT MONO (-925 1775);
DISPLAY INVISIBLE (-925 1775);
FORCEPROP 2 LAST PATH I21
J 0
(-950 1800);
DISPLAY 1.021277 (-950 1800);
PAINT ORANGE (-950 1800);
DISPLAY INVISIBLE (-950 1800);
FORCEPROP 2 LAST ROOM PVCCIN_CPU0_PWR_VR
J 0
(-1525 1800);
DISPLAY 1.936170 (-1525 1800);
PAINT ORANGE (-1525 1800);
DISPLAY INVISIBLE (-1525 1800);
FORCEPROP 2 LAST CDS_LIB mstr_standard
J 0
(-1125 1725);
PAINT ORANGE (-1125 1725);
DISPLAY INVISIBLE (-1125 1725);
FORCEADD INDUCTOR..1
(-1650 900);
FORCEPROP 1 LAST LOCATION L4D1
J 0
(-1675 950);
DISPLAY 0.617021 (-1675 950);
PAINT AQUA (-1675 950);
FORCEPROP 1 LASTPIN (-1750 900) $PN 1
J 0
(-1750 910);
DISPLAY 0.617021 (-1750 910);
PAINT WHITE (-1750 910);
FORCEPROP 1 LAST VALUE 0.12UH
J 2
(-1655 790);
DISPLAY 0.617021 (-1655 790);
PAINT SKYBLUE (-1655 790);
FORCEPROP 1 LAST PART_NUMBER D92183-034
J 0
(-1775 850);
DISPLAY 0.617021 (-1775 850);
PAINT BLUE (-1775 850);
FORCEPROP 1 LASTPIN (-1550 900) $PN 2
J 2
(-1540 910);
DISPLAY 0.617021 (-1540 910);
PAINT WHITE (-1540 910);
FORCEPROP 1 LAST PACK_TYPE SM
J 0
(-1485 790);
DISPLAY 0.617021 (-1485 790);
PAINT SKYBLUE (-1485 790);
FORCEPROP 1 LAST MATERIAL IND
J 0
(-1610 790);
DISPLAY 0.617021 (-1610 790);
PAINT SKYBLUE (-1610 790);
FORCEPROP 2 LAST CDS_LOCATION L4D1
J 0
(-1750 950);
DISPLAY 0.617021 (-1750 950);
PAINT AQUA (-1750 950);
DISPLAY INVISIBLE (-1750 950);
FORCEPROP 2 LAST CDS_LIB mstr_discrete
J 0
(-1650 900);
PAINT ORANGE (-1650 900);
DISPLAY INVISIBLE (-1650 900);
FORCEPROP 2 LAST ROOM PVCCIN_CPU0_PWR_VR
J 0
(-1750 1000);
DISPLAY 1.361702 (-1750 1000);
PAINT ORANGE (-1750 1000);
DISPLAY INVISIBLE (-1750 1000);
FORCEPROP 1 LAST PATH I24
J 0
(-1750 1050);
DISPLAY 0.978723 (-1750 1050);
PAINT ORANGE (-1750 1050);
DISPLAY INVISIBLE (-1750 1050);
FORCEPROP 2 LAST $SEC 1
J 0
(-1750 1100);
PAINT MONO (-1750 1100);
DISPLAY INVISIBLE (-1750 1100);
FORCEPROP 2 LAST CDS_SEC 1
J 0
(-1750 1100);
PAINT MONO (-1750 1100);
DISPLAY INVISIBLE (-1750 1100);
FORCEADD CAP_A..1
(-1025 600);
FORCEPROP 1 LAST PART_NUMBER E15431-004
J 0
(-975 450);
DISPLAY 0.617021 (-975 450);
PAINT BLUE (-975 450);
FORCEPROP 1 LAST TOLERANCE 20%
J 0
(-975 550);
DISPLAY 0.617021 (-975 550);
PAINT SKYBLUE (-975 550);
FORCEPROP 1 LAST VALUE 22.0UF
J 0
(-975 650);
DISPLAY 0.617021 (-975 650);
PAINT SKYBLUE (-975 650);
FORCEPROP 1 LAST LOCATION C6P3
J 0
(-975 700);
DISPLAY 0.617021 (-975 700);
PAINT AQUA (-975 700);
FORCEPROP 1 LAST PACK_TYPE 0603V
J 0
(-975 400);
DISPLAY 0.617021 (-975 400);
PAINT SKYBLUE (-975 400);
FORCEPROP 1 LAST MATERIAL X6S
J 0
(-975 500);
DISPLAY 0.617021 (-975 500);
PAINT SKYBLUE (-975 500);
FORCEPROP 1 LAST VOLTAGE 4V
J 0
(-975 600);
DISPLAY 0.617021 (-975 600);
PAINT SKYBLUE (-975 600);
FORCEPROP 1 LASTPIN (-1025 700) $PN 1
J 0
(-1015 680);
DISPLAY 0.617021 (-1015 680);
PAINT ORANGE (-1015 680);
FORCEPROP 1 LASTPIN (-1025 500) $PN 2
J 0
(-1015 480);
DISPLAY 0.617021 (-1015 480);
PAINT ORANGE (-1015 480);
FORCEPROP 2 LAST CDS_LOCATION C6P3
J 0
(-975 700);
DISPLAY 0.617021 (-975 700);
PAINT AQUA (-975 700);
DISPLAY INVISIBLE (-975 700);
FORCEPROP 2 LAST BOM_COST PROC_VRD_VCCIN_CPU0
J 0
(-975 750);
DISPLAY 1.446809 (-975 750);
PAINT MONO (-975 750);
DISPLAY INVISIBLE (-975 750);
FORCEPROP 2 LAST CDS_SEC 1
J 0
(-975 750);
PAINT ORANGE (-975 750);
DISPLAY INVISIBLE (-975 750);
FORCEPROP 2 LAST SEC_TYPE 0603V
J 0
(-970 800);
DISPLAY 1.021277 (-970 800);
PAINT ORANGE (-970 800);
DISPLAY INVISIBLE (-970 800);
FORCEPROP 2 LAST SEC 1
J 0
(-970 800);
DISPLAY 0.680851 (-970 800);
PAINT MONO (-970 800);
DISPLAY INVISIBLE (-970 800);
FORCEPROP 1 LAST PATH I25
J 0
(-975 750);
DISPLAY 0.978723 (-975 750);
PAINT WHITE (-975 750);
DISPLAY INVISIBLE (-975 750);
FORCEPROP 2 LAST ROOM PVCCIN_CPU0_PWR_VR
J 0
(-975 750);
DISPLAY 1.446809 (-975 750);
PAINT MONO (-975 750);
DISPLAY INVISIBLE (-975 750);
FORCEPROP 2 LAST CDS_LIB dev_discrete
J 0
(-1025 600);
PAINT ORANGE (-1025 600);
DISPLAY INVISIBLE (-1025 600);
FORCEADD GND..1
(-1025 350);
FORCEPROP 3 LASTPIN (-1025 400) SIG_NAME GND\g
J 0
(-1015 410);
DISPLAY 0.659574 (-1015 410);
PAINT MONO (-1015 410);
DISPLAY INVISIBLE (-1015 410);
FORCEPROP 1 LAST HDL_POWER GND
J 0
(-1025 500);
DISPLAY 1.723404 (-1025 500);
PAINT GREEN (-1025 500);
DISPLAY INVISIBLE (-1025 500);
FORCEPROP 1 LAST BODY_TYPE PLUMBING
J 0
(-1070 307);
DISPLAY 0.340426 (-1070 307);
PAINT GREEN (-1070 307);
DISPLAY INVISIBLE (-1070 307);
FORCEPROP 1 LAST SIZE 1B
J 0
(-950 300);
DISPLAY 1.723404 (-950 300);
PAINT GREEN (-950 300);
DISPLAY INVISIBLE (-950 300);
FORCEPROP 1 LAST PATH I26
J 0
(-950 350);
DISPLAY 0.872340 (-950 350);
PAINT AQUA (-950 350);
DISPLAY INVISIBLE (-950 350);
FORCEPROP 1 LAST VOLTAGE 0
J 0
(-1025 350);
PAINT SKYBLUE (-1025 350);
DISPLAY INVISIBLE (-1025 350);
FORCEPROP 2 LAST CDS_LIB mstr_symbols
J 0
(-1025 350);
PAINT ORANGE (-1025 350);
DISPLAY INVISIBLE (-1025 350);
FORCEPROP 2 LAST BOM_COST PROC_VRD_VCCIN_CPU0
J 0
(-1400 425);
DISPLAY 1.446809 (-1400 425);
PAINT MONO (-1400 425);
DISPLAY INVISIBLE (-1400 425);
FORCEPROP 2 LAST ROOM PVCCIN_CPU0_PWR_VR
J 0
(-1575 425);
DISPLAY 1.936170 (-1575 425);
PAINT ORANGE (-1575 425);
DISPLAY INVISIBLE (-1575 425);
FORCEADD GND..1
(-2700 3250);
FORCEPROP 3 LASTPIN (-2700 3300) SIG_NAME GND\g
J 0
(-2690 3310);
DISPLAY 0.659574 (-2690 3310);
PAINT MONO (-2690 3310);
DISPLAY INVISIBLE (-2690 3310);
FORCEPROP 1 LAST HDL_POWER GND
J 0
(-2700 3400);
DISPLAY 1.723404 (-2700 3400);
PAINT GREEN (-2700 3400);
DISPLAY INVISIBLE (-2700 3400);
FORCEPROP 1 LAST BODY_TYPE PLUMBING
J 0
(-2745 3207);
DISPLAY 0.340426 (-2745 3207);
PAINT GREEN (-2745 3207);
DISPLAY INVISIBLE (-2745 3207);
FORCEPROP 2 LAST CDS_LIB mstr_symbols
J 0
(-2700 3250);
DISPLAY 1.936170 (-2700 3250);
PAINT ORANGE (-2700 3250);
DISPLAY INVISIBLE (-2700 3250);
FORCEPROP 1 LAST SIZE 1B
J 0
(-2625 3200);
DISPLAY 1.723404 (-2625 3200);
PAINT GREEN (-2625 3200);
DISPLAY INVISIBLE (-2625 3200);
FORCEPROP 1 LAST VOLTAGE 0
J 0
(-2700 3250);
PAINT SKYBLUE (-2700 3250);
DISPLAY INVISIBLE (-2700 3250);
FORCEPROP 1 LAST PATH I27
J 0
(-2625 3250);
DISPLAY 0.872340 (-2625 3250);
PAINT AQUA (-2625 3250);
DISPLAY INVISIBLE (-2625 3250);
FORCEPROP 2 LAST BOM_COST PROC_VRD_VCCIN_CPU0
J 0
(-3075 3325);
DISPLAY 1.446809 (-3075 3325);
PAINT MONO (-3075 3325);
DISPLAY INVISIBLE (-3075 3325);
FORCEPROP 2 LAST ROOM PVCCIN_CPU0_PWR_VR
J 0
(-3250 3325);
DISPLAY 1.936170 (-3250 3325);
PAINT ORANGE (-3250 3325);
DISPLAY INVISIBLE (-3250 3325);
FORCEADD CAPP..1
(-2075 2550);
FORCEPROP 1 LAST VALUE 470UF
J 0
(-2025 2600);
DISPLAY 0.617021 (-2025 2600);
PAINT SKYBLUE (-2025 2600);
FORCEPROP 1 LAST TOLERANCE 20%
J 0
(-2025 2550);
DISPLAY 0.617021 (-2025 2550);
PAINT SKYBLUE (-2025 2550);
FORCEPROP 1 LAST MATERIAL ALUM
J 0
(-2025 2450);
DISPLAY 0.617021 (-2025 2450);
PAINT SKYBLUE (-2025 2450);
FORCEPROP 1 LAST PACK_TYPE 3018
J 0
(-2025 2400);
DISPLAY 0.617021 (-2025 2400);
PAINT SKYBLUE (-2025 2400);
FORCEPROP 1 LASTPIN (-2075 2450) $PN 2
J 0
(-2065 2435);
DISPLAY 0.617021 (-2065 2435);
PAINT GREEN (-2065 2435);
FORCEPROP 1 LASTPIN (-2075 2650) $PN 1
J 0
(-2065 2635);
DISPLAY 0.617021 (-2065 2635);
PAINT GREEN (-2065 2635);
FORCEPROP 1 LAST LOCATION C6P23
J 0
(-2025 2650);
DISPLAY 0.617021 (-2025 2650);
PAINT AQUA (-2025 2650);
FORCEPROP 1 LAST PART_NUMBER 699013-049
J 0
(-2025 2350);
DISPLAY 0.617021 (-2025 2350);
PAINT BLUE (-2025 2350);
FORCEPROP 2 LAST SEC_TYPE 3018
J 0
(-2010 2760);
DISPLAY 1.021277 (-2010 2760);
PAINT ORANGE (-2010 2760);
DISPLAY INVISIBLE (-2010 2760);
FORCEPROP 2 LAST BOM_COST PROC_VRD_VCCIN_CPU0
J 0
(-2025 2700);
PAINT MONO (-2025 2700);
DISPLAY INVISIBLE (-2025 2700);
FORCEPROP 2 LAST SEC 1
J 0
(-2025 2750);
PAINT MONO (-2025 2750);
DISPLAY INVISIBLE (-2025 2750);
FORCEPROP 2 LAST CDS_LOCATION C6P23
J 0
(-2025 2650);
DISPLAY 0.617021 (-2025 2650);
PAINT AQUA (-2025 2650);
DISPLAY INVISIBLE (-2025 2650);
FORCEPROP 1 LAST PATH I28
J 0
(-2025 2700);
DISPLAY 0.978723 (-2025 2700);
PAINT ORANGE (-2025 2700);
DISPLAY INVISIBLE (-2025 2700);
FORCEPROP 2 LAST ROOM PVCCIN_CPU0_DECAP_VR
J 0
(-2025 2675);
PAINT MONO (-2025 2675);
DISPLAY INVISIBLE (-2025 2675);
FORCEPROP 1 LAST VOLTAGE 2.5V
J 0
(-2025 2500);
PAINT SKYBLUE (-2025 2500);
DISPLAY INVISIBLE (-2025 2500);
FORCEPROP 2 LAST CDS_LIB mstr_discrete
J 0
(-2075 2550);
PAINT MONO (-2075 2550);
DISPLAY INVISIBLE (-2075 2550);
FORCEADD CAPP..1
(-2525 2575);
FORCEPROP 1 LAST PACK_TYPE 3018
J 0
(-2475 2425);
DISPLAY 0.617021 (-2475 2425);
PAINT SKYBLUE (-2475 2425);
FORCEPROP 1 LAST VALUE 470UF
J 0
(-2475 2625);
DISPLAY 0.617021 (-2475 2625);
PAINT SKYBLUE (-2475 2625);
FORCEPROP 1 LASTPIN (-2525 2675) $PN 1
J 0
(-2515 2660);
DISPLAY 0.617021 (-2515 2660);
PAINT GREEN (-2515 2660);
FORCEPROP 1 LASTPIN (-2525 2475) $PN 2
J 0
(-2515 2460);
DISPLAY 0.617021 (-2515 2460);
PAINT GREEN (-2515 2460);
FORCEPROP 1 LAST PART_NUMBER 699013-049
J 0
(-2475 2375);
DISPLAY 0.617021 (-2475 2375);
PAINT BLUE (-2475 2375);
FORCEPROP 1 LAST MATERIAL ALUM
J 0
(-2475 2475);
DISPLAY 0.617021 (-2475 2475);
PAINT SKYBLUE (-2475 2475);
FORCEPROP 1 LAST TOLERANCE 20%
J 0
(-2475 2575);
DISPLAY 0.617021 (-2475 2575);
PAINT SKYBLUE (-2475 2575);
FORCEPROP 1 LAST LOCATION C6P14
J 0
(-2475 2675);
DISPLAY 0.617021 (-2475 2675);
PAINT AQUA (-2475 2675);
FORCEPROP 2 LAST SEC_TYPE 3018
J 0
(-2460 2785);
DISPLAY 1.021277 (-2460 2785);
PAINT ORANGE (-2460 2785);
DISPLAY INVISIBLE (-2460 2785);
FORCEPROP 2 LAST SEC 1
J 0
(-2475 2775);
PAINT MONO (-2475 2775);
DISPLAY INVISIBLE (-2475 2775);
FORCEPROP 2 LAST BOM_COST PROC_VRD_VCCIN_CPU0
J 0
(-2475 2725);
PAINT MONO (-2475 2725);
DISPLAY INVISIBLE (-2475 2725);
FORCEPROP 1 LAST PATH I29
J 0
(-2475 2725);
DISPLAY 0.978723 (-2475 2725);
PAINT ORANGE (-2475 2725);
DISPLAY INVISIBLE (-2475 2725);
FORCEPROP 2 LAST ROOM PVCCIN_CPU0_DECAP_VR
J 0
(-2475 2700);
PAINT MONO (-2475 2700);
DISPLAY INVISIBLE (-2475 2700);
FORCEPROP 2 LAST CDS_LOCATION C6P14
J 0
(-2475 2675);
DISPLAY 0.617021 (-2475 2675);
PAINT AQUA (-2475 2675);
DISPLAY INVISIBLE (-2475 2675);
FORCEPROP 2 LAST CDS_LIB mstr_discrete
J 0
(-2525 2575);
PAINT MONO (-2525 2575);
DISPLAY INVISIBLE (-2525 2575);
FORCEPROP 1 LAST VOLTAGE 2.5V
J 0
(-2475 2525);
PAINT SKYBLUE (-2475 2525);
DISPLAY INVISIBLE (-2475 2525);
FORCEADD CAP..1
R 2
(-6100 800);
FORCEPROP 1 LASTPIN (-6100 700) $PN 2
J 2
(-6110 680);
DISPLAY 0.617021 (-6110 680);
PAINT ORANGE (-6110 680);
FORCEPROP 1 LAST PACK_TYPE 0402
J 2
(-6150 600);
DISPLAY 0.617021 (-6150 600);
PAINT SKYBLUE (-6150 600);
FORCEPROP 1 LAST VOLTAGE 16V
J 2
(-6150 800);
DISPLAY 0.617021 (-6150 800);
PAINT SKYBLUE (-6150 800);
FORCEPROP 1 LAST TOLERANCE 10%
J 2
(-6150 750);
DISPLAY 0.617021 (-6150 750);
PAINT SKYBLUE (-6150 750);
FORCEPROP 1 LASTPIN (-6100 900) $PN 1
J 2
(-6110 880);
DISPLAY 0.617021 (-6110 880);
PAINT ORANGE (-6110 880);
FORCEPROP 1 LAST LOCATION C4D9
J 2
(-6150 900);
DISPLAY 0.617021 (-6150 900);
PAINT AQUA (-6150 900);
FORCEPROP 1 LAST VALUE 0.220UF
J 2
(-6150 850);
DISPLAY 0.617021 (-6150 850);
PAINT SKYBLUE (-6150 850);
FORCEPROP 1 LAST MATERIAL X7R
J 2
(-6150 700);
DISPLAY 0.617021 (-6150 700);
PAINT SKYBLUE (-6150 700);
FORCEPROP 1 LAST PART_NUMBER A36096-104
J 2
(-6150 650);
DISPLAY 0.617021 (-6150 650);
PAINT BLUE (-6150 650);
FORCEPROP 2 LAST NO_XNET_CONNECTION 1
J 0
(-6150 1000);
PAINT MONO (-6150 1000);
DISPLAY INVISIBLE (-6150 1000);
FORCEPROP 2 LAST SEC 1
J 0
(-6150 1000);
DISPLAY 0.680851 (-6150 1000);
PAINT MONO (-6150 1000);
DISPLAY INVISIBLE (-6150 1000);
FORCEPROP 2 LAST SEC_TYPE 0402
J 0
(-6150 1000);
DISPLAY 1.021277 (-6150 1000);
PAINT ORANGE (-6150 1000);
DISPLAY INVISIBLE (-6150 1000);
FORCEPROP 0 LAST SPOF TRUE
J 0
(-6150 1000);
DISPLAY 1.021277 (-6150 1000);
PAINT ORANGE (-6150 1000);
DISPLAY INVISIBLE (-6150 1000);
FORCEPROP 2 LAST ROOM PVCCIN_CPU0_PWR_VR
J 0
(-6150 950);
DISPLAY 1.361702 (-6150 950);
PAINT ORANGE (-6150 950);
DISPLAY INVISIBLE (-6150 950);
FORCEPROP 1 LAST PATH I3
J 2
(-6150 950);
DISPLAY 0.978723 (-6150 950);
PAINT WHITE (-6150 950);
DISPLAY INVISIBLE (-6150 950);
FORCEPROP 2 LAST CDS_LOCATION C4D9
J 2
(-6150 900);
DISPLAY 0.617021 (-6150 900);
PAINT AQUA (-6150 900);
DISPLAY INVISIBLE (-6150 900);
FORCEPROP 2 LAST CDS_LIB mstr_discrete
J 0
(-6100 800);
PAINT ORANGE (-6100 800);
DISPLAY INVISIBLE (-6100 800);
FORCEADD CAPP..1
(-2975 2575);
FORCEPROP 1 LAST LOCATION C6P18
J 0
(-2925 2675);
DISPLAY 0.617021 (-2925 2675);
PAINT AQUA (-2925 2675);
FORCEPROP 1 LAST VALUE 470UF
J 0
(-2925 2625);
DISPLAY 0.617021 (-2925 2625);
PAINT SKYBLUE (-2925 2625);
FORCEPROP 1 LAST PART_NUMBER 699013-049
J 0
(-2925 2375);
DISPLAY 0.617021 (-2925 2375);
PAINT BLUE (-2925 2375);
FORCEPROP 1 LAST TOLERANCE 20%
J 0
(-2925 2575);
DISPLAY 0.617021 (-2925 2575);
PAINT SKYBLUE (-2925 2575);
FORCEPROP 1 LASTPIN (-2975 2675) $PN 1
J 0
(-2965 2660);
DISPLAY 0.617021 (-2965 2660);
PAINT GREEN (-2965 2660);
FORCEPROP 1 LAST PACK_TYPE 3018
J 0
(-2925 2425);
DISPLAY 0.617021 (-2925 2425);
PAINT SKYBLUE (-2925 2425);
FORCEPROP 1 LAST MATERIAL ALUM
J 0
(-2925 2475);
DISPLAY 0.617021 (-2925 2475);
PAINT SKYBLUE (-2925 2475);
FORCEPROP 1 LASTPIN (-2975 2475) $PN 2
J 0
(-2965 2460);
DISPLAY 0.617021 (-2965 2460);
PAINT GREEN (-2965 2460);
FORCEPROP 2 LAST SEC_TYPE 3018
J 0
(-2910 2785);
DISPLAY 1.021277 (-2910 2785);
PAINT ORANGE (-2910 2785);
DISPLAY INVISIBLE (-2910 2785);
FORCEPROP 2 LAST SEC 1
J 0
(-2925 2775);
PAINT MONO (-2925 2775);
DISPLAY INVISIBLE (-2925 2775);
FORCEPROP 2 LAST BOM_COST PROC_VRD_VCCIN_CPU0
J 0
(-2925 2725);
PAINT MONO (-2925 2725);
DISPLAY INVISIBLE (-2925 2725);
FORCEPROP 2 LAST CDS_LOCATION C6P18
J 0
(-2925 2675);
DISPLAY 0.617021 (-2925 2675);
PAINT AQUA (-2925 2675);
DISPLAY INVISIBLE (-2925 2675);
FORCEPROP 1 LAST PATH I30
J 0
(-2925 2725);
DISPLAY 0.978723 (-2925 2725);
PAINT ORANGE (-2925 2725);
DISPLAY INVISIBLE (-2925 2725);
FORCEPROP 2 LAST ROOM PVCCIN_CPU0_DECAP_VR
J 0
(-2925 2700);
PAINT MONO (-2925 2700);
DISPLAY INVISIBLE (-2925 2700);
FORCEPROP 2 LAST CDS_LIB mstr_discrete
J 0
(-2975 2575);
PAINT MONO (-2975 2575);
DISPLAY INVISIBLE (-2975 2575);
FORCEPROP 1 LAST VOLTAGE 2.5V
J 0
(-2925 2525);
PAINT SKYBLUE (-2925 2525);
DISPLAY INVISIBLE (-2925 2525);
FORCEADD CAPP..1
(-3425 2575);
FORCEPROP 1 LAST VALUE 470UF
J 0
(-3375 2625);
DISPLAY 0.617021 (-3375 2625);
PAINT SKYBLUE (-3375 2625);
FORCEPROP 1 LAST TOLERANCE 20%
J 0
(-3375 2575);
DISPLAY 0.617021 (-3375 2575);
PAINT SKYBLUE (-3375 2575);
FORCEPROP 1 LAST PART_NUMBER 699013-049
J 0
(-3375 2375);
DISPLAY 0.617021 (-3375 2375);
PAINT BLUE (-3375 2375);
FORCEPROP 1 LAST LOCATION C6P8
J 0
(-3375 2675);
DISPLAY 0.617021 (-3375 2675);
PAINT AQUA (-3375 2675);
FORCEPROP 1 LASTPIN (-3425 2675) $PN 1
J 0
(-3415 2660);
DISPLAY 0.617021 (-3415 2660);
PAINT GREEN (-3415 2660);
FORCEPROP 1 LAST PACK_TYPE 3018
J 0
(-3375 2425);
DISPLAY 0.617021 (-3375 2425);
PAINT SKYBLUE (-3375 2425);
FORCEPROP 1 LAST MATERIAL ALUM
J 0
(-3375 2475);
DISPLAY 0.617021 (-3375 2475);
PAINT SKYBLUE (-3375 2475);
FORCEPROP 1 LASTPIN (-3425 2475) $PN 2
J 0
(-3415 2460);
DISPLAY 0.617021 (-3415 2460);
PAINT GREEN (-3415 2460);
FORCEPROP 2 LAST SEC_TYPE 3018
J 0
(-3360 2785);
DISPLAY 1.021277 (-3360 2785);
PAINT ORANGE (-3360 2785);
DISPLAY INVISIBLE (-3360 2785);
FORCEPROP 2 LAST SEC 1
J 0
(-3375 2775);
PAINT MONO (-3375 2775);
DISPLAY INVISIBLE (-3375 2775);
FORCEPROP 2 LAST BOM_COST PROC_VRD_VCCIN_CPU0
J 0
(-3375 2725);
PAINT MONO (-3375 2725);
DISPLAY INVISIBLE (-3375 2725);
FORCEPROP 1 LAST PATH I32
J 0
(-3375 2725);
DISPLAY 0.978723 (-3375 2725);
PAINT ORANGE (-3375 2725);
DISPLAY INVISIBLE (-3375 2725);
FORCEPROP 2 LAST ROOM PVCCIN_CPU0_DECAP_VR
J 0
(-3375 2700);
PAINT MONO (-3375 2700);
DISPLAY INVISIBLE (-3375 2700);
FORCEPROP 2 LAST CDS_LOCATION C6P8
J 0
(-3375 2675);
DISPLAY 0.617021 (-3375 2675);
PAINT AQUA (-3375 2675);
DISPLAY INVISIBLE (-3375 2675);
FORCEPROP 2 LAST CDS_LIB mstr_discrete
J 0
(-3425 2575);
PAINT MONO (-3425 2575);
DISPLAY INVISIBLE (-3425 2575);
FORCEPROP 1 LAST VOLTAGE 2.5V
J 0
(-3375 2525);
PAINT SKYBLUE (-3375 2525);
DISPLAY INVISIBLE (-3375 2525);
FORCEADD PVCCIN_CPU0..1
(-3850 2850);
FORCEPROP 3 LASTPIN (-3850 2800) SIG_NAME PVCCIN_CPU0\g
J 0
(-3840 2810);
DISPLAY 0.659574 (-3840 2810);
PAINT MONO (-3840 2810);
DISPLAY INVISIBLE (-3840 2810);
FORCEPROP 1 LAST HDL_POWER PVCCIN_CPU0
J 1
(-3850 2900);
DISPLAY 0.872340 (-3850 2900);
PAINT GREEN (-3850 2900);
DISPLAY INVISIBLE (-3850 2900);
FORCEPROP 1 LAST BODY_TYPE PLUMBING
J 0
(-3895 2807);
DISPLAY 0.340426 (-3895 2807);
PAINT GREEN (-3895 2807);
DISPLAY INVISIBLE (-3895 2807);
FORCEPROP 1 LAST PATH I33
J 0
(-3800 2875);
DISPLAY 0.872340 (-3800 2875);
PAINT AQUA (-3800 2875);
DISPLAY INVISIBLE (-3800 2875);
FORCEPROP 2 LAST CDS_LIB mstr_symbols
J 0
(-3850 2850);
PAINT ORANGE (-3850 2850);
DISPLAY INVISIBLE (-3850 2850);
FORCEPROP 1 LAST VOLTAGE 2.0V
J 0
(-3895 2807);
DISPLAY 0.340426 (-3895 2807);
PAINT SKYBLUE (-3895 2807);
DISPLAY INVISIBLE (-3895 2807);
FORCEADD CAPP..1
(-3850 2575);
FORCEPROP 1 LAST PART_NUMBER 699013-049
J 0
(-3800 2375);
DISPLAY 0.617021 (-3800 2375);
PAINT BLUE (-3800 2375);
FORCEPROP 1 LAST LOCATION C6N9
J 0
(-3800 2675);
DISPLAY 0.617021 (-3800 2675);
PAINT AQUA (-3800 2675);
FORCEPROP 1 LAST VALUE 470UF
J 0
(-3800 2625);
DISPLAY 0.617021 (-3800 2625);
PAINT SKYBLUE (-3800 2625);
FORCEPROP 1 LAST TOLERANCE 20%
J 0
(-3800 2575);
DISPLAY 0.617021 (-3800 2575);
PAINT SKYBLUE (-3800 2575);
FORCEPROP 1 LASTPIN (-3850 2675) $PN 1
J 0
(-3840 2660);
DISPLAY 0.617021 (-3840 2660);
PAINT GREEN (-3840 2660);
FORCEPROP 1 LAST PACK_TYPE 3018
J 0
(-3800 2425);
DISPLAY 0.617021 (-3800 2425);
PAINT SKYBLUE (-3800 2425);
FORCEPROP 1 LAST VOLTAGE 2.5V
J 0
(-3800 2525);
DISPLAY 0.617021 (-3800 2525);
PAINT SKYBLUE (-3800 2525);
FORCEPROP 1 LAST MATERIAL ALUM
J 0
(-3800 2475);
DISPLAY 0.617021 (-3800 2475);
PAINT SKYBLUE (-3800 2475);
FORCEPROP 1 LASTPIN (-3850 2475) $PN 2
J 0
(-3840 2460);
DISPLAY 0.617021 (-3840 2460);
PAINT GREEN (-3840 2460);
FORCEPROP 2 LAST SEC_TYPE 3018
J 0
(-3785 2785);
DISPLAY 1.021277 (-3785 2785);
PAINT ORANGE (-3785 2785);
DISPLAY INVISIBLE (-3785 2785);
FORCEPROP 2 LAST BOM_COST PROC_VRD_VCCIN_CPU0
J 0
(-3800 2725);
PAINT MONO (-3800 2725);
DISPLAY INVISIBLE (-3800 2725);
FORCEPROP 2 LAST SEC 1
J 0
(-3800 2775);
PAINT MONO (-3800 2775);
DISPLAY INVISIBLE (-3800 2775);
FORCEPROP 2 LAST CDS_LOCATION C6N9
J 0
(-3800 2675);
DISPLAY 0.617021 (-3800 2675);
PAINT AQUA (-3800 2675);
DISPLAY INVISIBLE (-3800 2675);
FORCEPROP 1 LAST PATH I34
J 0
(-3800 2725);
DISPLAY 0.978723 (-3800 2725);
PAINT ORANGE (-3800 2725);
DISPLAY INVISIBLE (-3800 2725);
FORCEPROP 2 LAST ROOM PVCCIN_CPU0_DECAP_VR
J 0
(-3800 2700);
PAINT MONO (-3800 2700);
DISPLAY INVISIBLE (-3800 2700);
FORCEPROP 2 LAST CDS_LIB mstr_discrete
J 0
(-3850 2575);
PAINT MONO (-3850 2575);
DISPLAY INVISIBLE (-3850 2575);
FORCEADD RES..1
(-5850 4725);
FORCEPROP 1 LAST PART_NUMBER G21796-090
J 0
(-5975 4650);
DISPLAY 0.617021 (-5975 4650);
PAINT BLUE (-5975 4650);
FORCEPROP 1 LAST MATERIAL CHIP
J 0
(-5775 4550);
DISPLAY 0.617021 (-5775 4550);
PAINT SKYBLUE (-5775 4550);
FORCEPROP 1 LASTPIN (-5750 4725) $PN 2
J 0
(-5788 4737);
DISPLAY 0.617021 (-5788 4737);
PAINT ORANGE (-5788 4737);
FORCEPROP 1 LAST LOCATION R6P19
J 0
(-5900 4775);
DISPLAY 0.617021 (-5900 4775);
PAINT AQUA (-5900 4775);
FORCEPROP 1 LASTPIN (-5950 4725) $PN 1
J 0
(-5938 4737);
DISPLAY 0.617021 (-5938 4737);
PAINT ORANGE (-5938 4737);
FORCEPROP 1 LAST VALUE 1.0
J 2
(-5950 4600);
DISPLAY 0.617021 (-5950 4600);
PAINT SKYBLUE (-5950 4600);
FORCEPROP 1 LAST TOLERANCE 1%
J 0
(-5900 4600);
DISPLAY 0.617021 (-5900 4600);
PAINT SKYBLUE (-5900 4600);
FORCEPROP 1 LAST PACK_TYPE 0402
J 0
(-5800 4600);
DISPLAY 0.617021 (-5800 4600);
PAINT SKYBLUE (-5800 4600);
FORCEPROP 1 LAST WATTAGE 1/16W
J 2
(-5825 4550);
DISPLAY 0.617021 (-5825 4550);
PAINT SKYBLUE (-5825 4550);
FORCEPROP 2 LAST CDS_LIB mstr_discrete
J 0
(-5850 4725);
PAINT ORANGE (-5850 4725);
DISPLAY INVISIBLE (-5850 4725);
FORCEPROP 2 LAST ROOM PVCCIN_CPU0_PWR_VR
J 0
(-5900 4825);
DISPLAY 1.361702 (-5900 4825);
PAINT ORANGE (-5900 4825);
DISPLAY INVISIBLE (-5900 4825);
FORCEPROP 2 LAST SEC 1
J 0
(-5900 4925);
DISPLAY 0.680851 (-5900 4925);
PAINT MONO (-5900 4925);
DISPLAY INVISIBLE (-5900 4925);
FORCEPROP 2 LAST CDS_LOCATION R6P19
J 0
(-5900 4775);
DISPLAY 0.617021 (-5900 4775);
PAINT AQUA (-5900 4775);
DISPLAY INVISIBLE (-5900 4775);
FORCEPROP 1 LAST PATH I38
J 0
(-5900 4875);
DISPLAY 0.978723 (-5900 4875);
PAINT WHITE (-5900 4875);
DISPLAY INVISIBLE (-5900 4875);
FORCEPROP 2 LAST SEC_TYPE 0402
J 0
(-5900 4925);
DISPLAY 1.021277 (-5900 4925);
PAINT ORANGE (-5900 4925);
DISPLAY INVISIBLE (-5900 4925);
FORCEADD VCC_CORE..1
(-7425 4600);
FORCEPROP 3 LASTPIN (-7425 4550) SIG_NAME VR_FET_SW_P12V_STBY_PVCCIN_CPU0\g
J 0
(-7415 4560);
DISPLAY 0.659574 (-7415 4560);
PAINT MONO (-7415 4560);
DISPLAY INVISIBLE (-7415 4560);
FORCEPROP 1 LAST HDL_POWER VR_FET_SW_P12V_STBY_PVCCIN_CPU0
J 1
(-7375 4650);
DISPLAY 0.617021 (-7375 4650);
PAINT GREEN (-7375 4650);
FORCEPROP 1 LAST PATH I39
J 0
(-7375 4625);
DISPLAY 0.872340 (-7375 4625);
PAINT AQUA (-7375 4625);
DISPLAY INVISIBLE (-7375 4625);
FORCEPROP 2 LAST CDS_LIB mstr_symbols
J 0
(-7425 4600);
DISPLAY 1.936170 (-7425 4600);
PAINT ORANGE (-7425 4600);
DISPLAY INVISIBLE (-7425 4600);
FORCEADD CAP..1
(-5300 4125);
FORCEPROP 1 LAST TOLERANCE 10%
J 0
(-5250 4075);
DISPLAY 0.617021 (-5250 4075);
PAINT SKYBLUE (-5250 4075);
FORCEPROP 1 LAST LOCATION C4D13
J 0
(-5250 4225);
DISPLAY 0.617021 (-5250 4225);
PAINT AQUA (-5250 4225);
FORCEPROP 1 LAST VALUE 0.22UF
J 0
(-5250 4175);
DISPLAY 0.617021 (-5250 4175);
PAINT SKYBLUE (-5250 4175);
FORCEPROP 1 LAST VOLTAGE 16V
J 0
(-5250 4125);
DISPLAY 0.617021 (-5250 4125);
PAINT SKYBLUE (-5250 4125);
FORCEPROP 1 LASTPIN (-5300 4225) $PN 1
J 0
(-5290 4205);
DISPLAY 0.617021 (-5290 4205);
PAINT ORANGE (-5290 4205);
FORCEPROP 1 LAST PART_NUMBER A36096-155
J 0
(-5250 3975);
DISPLAY 0.617021 (-5250 3975);
PAINT BLUE (-5250 3975);
FORCEPROP 1 LAST PACK_TYPE 0402
J 0
(-5250 3925);
DISPLAY 0.617021 (-5250 3925);
PAINT SKYBLUE (-5250 3925);
FORCEPROP 1 LAST MATERIAL X7R
J 0
(-5250 4025);
DISPLAY 0.617021 (-5250 4025);
PAINT SKYBLUE (-5250 4025);
FORCEPROP 1 LASTPIN (-5300 4025) $PN 2
J 0
(-5290 4005);
DISPLAY 0.617021 (-5290 4005);
PAINT ORANGE (-5290 4005);
FORCEPROP 2 LAST SEC_TYPE 0402
J 0
(-5250 4325);
DISPLAY 1.021277 (-5250 4325);
PAINT ORANGE (-5250 4325);
DISPLAY INVISIBLE (-5250 4325);
FORCEPROP 2 LAST CDS_LIB mstr_discrete
J 0
(-5300 4125);
PAINT ORANGE (-5300 4125);
DISPLAY INVISIBLE (-5300 4125);
FORCEPROP 2 LAST SEC 1
J 0
(-5250 4325);
DISPLAY 0.680851 (-5250 4325);
PAINT MONO (-5250 4325);
DISPLAY INVISIBLE (-5250 4325);
FORCEPROP 2 LAST CDS_LOCATION C4D13
J 0
(-5250 4225);
DISPLAY 0.617021 (-5250 4225);
PAINT AQUA (-5250 4225);
DISPLAY INVISIBLE (-5250 4225);
FORCEPROP 1 LAST PATH I40
J 0
(-5250 4275);
DISPLAY 0.978723 (-5250 4275);
PAINT WHITE (-5250 4275);
DISPLAY INVISIBLE (-5250 4275);
FORCEPROP 2 LAST ROOM PVCCIN_CPU0_PWR_VR
J 0
(-5250 4275);
DISPLAY 1.361702 (-5250 4275);
PAINT ORANGE (-5250 4275);
DISPLAY INVISIBLE (-5250 4275);
FORCEADD CAP_A..1
R 2
(-5450 4150);
FORCEPROP 1 LAST TOLERANCE 10%
J 2
(-5500 4100);
DISPLAY 0.617021 (-5500 4100);
PAINT SKYBLUE (-5500 4100);
FORCEPROP 1 LAST VOLTAGE 6.3V
J 2
(-5500 4150);
DISPLAY 0.617021 (-5500 4150);
PAINT SKYBLUE (-5500 4150);
FORCEPROP 1 LASTPIN (-5450 4250) $PN 1
J 2
(-5460 4230);
DISPLAY 0.617021 (-5460 4230);
PAINT ORANGE (-5460 4230);
FORCEPROP 1 LAST LOCATION C4D14
J 2
(-5500 4250);
DISPLAY 0.617021 (-5500 4250);
PAINT AQUA (-5500 4250);
FORCEPROP 1 LAST VALUE 1.0UF
J 2
(-5500 4200);
DISPLAY 0.617021 (-5500 4200);
PAINT SKYBLUE (-5500 4200);
FORCEPROP 1 LASTPIN (-5450 4050) $PN 2
J 2
(-5460 4030);
DISPLAY 0.617021 (-5460 4030);
PAINT ORANGE (-5460 4030);
FORCEPROP 1 LAST MATERIAL X6S
J 2
(-5500 4050);
DISPLAY 0.617021 (-5500 4050);
PAINT SKYBLUE (-5500 4050);
FORCEPROP 1 LAST PACK_TYPE 0402V
J 2
(-5500 3950);
DISPLAY 0.617021 (-5500 3950);
PAINT SKYBLUE (-5500 3950);
FORCEPROP 1 LAST PART_NUMBER D97712-004
J 2
(-5500 4000);
DISPLAY 0.617021 (-5500 4000);
PAINT BLUE (-5500 4000);
FORCEPROP 2 LAST ROOM PVCCIN_CPU0_PWR_VR
J 0
(-5500 4300);
DISPLAY 1.361702 (-5500 4300);
PAINT ORANGE (-5500 4300);
DISPLAY INVISIBLE (-5500 4300);
FORCEPROP 2 LAST SEC 1
J 0
(-5500 4350);
DISPLAY 0.680851 (-5500 4350);
PAINT MONO (-5500 4350);
DISPLAY INVISIBLE (-5500 4350);
FORCEPROP 1 LAST PATH I41
J 2
(-5500 4300);
DISPLAY 0.978723 (-5500 4300);
PAINT WHITE (-5500 4300);
DISPLAY INVISIBLE (-5500 4300);
FORCEPROP 2 LAST CDS_LOCATION C4D14
J 2
(-5500 4250);
DISPLAY 0.617021 (-5500 4250);
PAINT AQUA (-5500 4250);
DISPLAY INVISIBLE (-5500 4250);
FORCEPROP 2 LAST CDS_SEC 1
J 0
(-5500 4300);
PAINT ORANGE (-5500 4300);
DISPLAY INVISIBLE (-5500 4300);
FORCEPROP 2 LAST CDS_LIB dev_discrete
J 0
(-5450 4150);
PAINT ORANGE (-5450 4150);
DISPLAY INVISIBLE (-5450 4150);
FORCEPROP 2 LAST SEC_TYPE 0402V
J 0
(-5500 4350);
DISPLAY 1.021277 (-5500 4350);
PAINT ORANGE (-5500 4350);
DISPLAY INVISIBLE (-5500 4350);
FORCEADD CAP..1
R 2
(-6025 3525);
FORCEPROP 1 LASTPIN (-6025 3625) $PN 1
J 2
(-6035 3605);
DISPLAY 0.617021 (-6035 3605);
PAINT ORANGE (-6035 3605);
FORCEPROP 1 LAST LOCATION C4D28
J 2
(-6075 3625);
DISPLAY 0.617021 (-6075 3625);
PAINT AQUA (-6075 3625);
FORCEPROP 1 LASTPIN (-6025 3425) $PN 2
J 2
(-6035 3405);
DISPLAY 0.617021 (-6035 3405);
PAINT ORANGE (-6035 3405);
FORCEPROP 1 LAST VOLTAGE 16V
J 2
(-6075 3525);
DISPLAY 0.617021 (-6075 3525);
PAINT SKYBLUE (-6075 3525);
FORCEPROP 1 LAST PACK_TYPE 0402
J 2
(-6075 3325);
DISPLAY 0.617021 (-6075 3325);
PAINT SKYBLUE (-6075 3325);
FORCEPROP 1 LAST TOLERANCE 10%
J 2
(-6075 3475);
DISPLAY 0.617021 (-6075 3475);
PAINT SKYBLUE (-6075 3475);
FORCEPROP 1 LAST MATERIAL X7R
J 2
(-6075 3425);
DISPLAY 0.617021 (-6075 3425);
PAINT SKYBLUE (-6075 3425);
FORCEPROP 1 LAST VALUE 0.220UF
J 2
(-6075 3575);
DISPLAY 0.617021 (-6075 3575);
PAINT SKYBLUE (-6075 3575);
FORCEPROP 1 LAST PART_NUMBER A36096-104
J 2
(-6075 3375);
DISPLAY 0.617021 (-6075 3375);
PAINT BLUE (-6075 3375);
FORCEPROP 2 LAST NO_XNET_CONNECTION 1
J 0
(-6075 3725);
PAINT MONO (-6075 3725);
DISPLAY INVISIBLE (-6075 3725);
FORCEPROP 1 LAST PATH I42
J 2
(-6075 3675);
DISPLAY 0.978723 (-6075 3675);
PAINT WHITE (-6075 3675);
DISPLAY INVISIBLE (-6075 3675);
FORCEPROP 2 LAST ROOM PVCCIN_CPU0_PWR_VR
J 0
(-6100 3675);
DISPLAY 1.361702 (-6100 3675);
PAINT ORANGE (-6100 3675);
DISPLAY INVISIBLE (-6100 3675);
FORCEPROP 2 LAST CDS_LOCATION C4D28
J 2
(-6075 3625);
DISPLAY 0.617021 (-6075 3625);
PAINT AQUA (-6075 3625);
DISPLAY INVISIBLE (-6075 3625);
FORCEPROP 2 LAST SEC 1
J 0
(-6075 3725);
DISPLAY 0.680851 (-6075 3725);
PAINT MONO (-6075 3725);
DISPLAY INVISIBLE (-6075 3725);
FORCEPROP 0 LAST SPOF TRUE
J 0
(-6075 3725);
DISPLAY 1.021277 (-6075 3725);
PAINT ORANGE (-6075 3725);
DISPLAY INVISIBLE (-6075 3725);
FORCEPROP 2 LAST SEC_TYPE 0402
J 0
(-6075 3725);
DISPLAY 1.021277 (-6075 3725);
PAINT ORANGE (-6075 3725);
DISPLAY INVISIBLE (-6075 3725);
FORCEPROP 2 LAST CDS_LIB mstr_discrete
J 0
(-6025 3525);
PAINT ORANGE (-6025 3525);
DISPLAY INVISIBLE (-6025 3525);
FORCEADD CAP..1
(-6075 4125);
FORCEPROP 1 LAST PART_NUMBER D97712-011
J 0
(-6025 3975);
DISPLAY 0.617021 (-6025 3975);
PAINT BLUE (-6025 3975);
FORCEPROP 1 LAST MATERIAL X6S
J 0
(-6025 4025);
DISPLAY 0.617021 (-6025 4025);
PAINT SKYBLUE (-6025 4025);
FORCEPROP 1 LAST LOCATION C4D16
J 0
(-6025 4225);
DISPLAY 0.617021 (-6025 4225);
PAINT AQUA (-6025 4225);
FORCEPROP 1 LAST VALUE 1.0UF
J 0
(-6025 4175);
DISPLAY 0.617021 (-6025 4175);
PAINT SKYBLUE (-6025 4175);
FORCEPROP 1 LAST VOLTAGE 16V
J 0
(-6025 4125);
DISPLAY 0.617021 (-6025 4125);
PAINT SKYBLUE (-6025 4125);
FORCEPROP 1 LASTPIN (-6075 4225) $PN 1
J 0
(-6065 4205);
DISPLAY 0.617021 (-6065 4205);
PAINT ORANGE (-6065 4205);
FORCEPROP 1 LAST TOLERANCE 10%
J 0
(-6025 4075);
DISPLAY 0.617021 (-6025 4075);
PAINT SKYBLUE (-6025 4075);
FORCEPROP 1 LASTPIN (-6075 4025) $PN 2
J 0
(-6065 4005);
DISPLAY 0.617021 (-6065 4005);
PAINT ORANGE (-6065 4005);
FORCEPROP 1 LAST PACK_TYPE 0402
J 0
(-6025 3925);
DISPLAY 0.617021 (-6025 3925);
PAINT SKYBLUE (-6025 3925);
FORCEPROP 2 LAST SEC_TYPE 0402
J 0
(-6025 4325);
DISPLAY 1.021277 (-6025 4325);
PAINT ORANGE (-6025 4325);
DISPLAY INVISIBLE (-6025 4325);
FORCEPROP 2 LAST SEC 1
J 0
(-6025 4325);
DISPLAY 0.680851 (-6025 4325);
PAINT MONO (-6025 4325);
DISPLAY INVISIBLE (-6025 4325);
FORCEPROP 2 LAST CDS_LIB mstr_discrete
J 0
(-6075 4125);
PAINT ORANGE (-6075 4125);
DISPLAY INVISIBLE (-6075 4125);
FORCEPROP 2 LAST CDS_LOCATION C4D16
J 0
(-6025 4225);
DISPLAY 0.617021 (-6025 4225);
PAINT AQUA (-6025 4225);
DISPLAY INVISIBLE (-6025 4225);
FORCEPROP 1 LAST PATH I45
J 0
(-6025 4275);
DISPLAY 0.978723 (-6025 4275);
PAINT WHITE (-6025 4275);
DISPLAY INVISIBLE (-6025 4275);
FORCEPROP 2 LAST ROOM PVCCIN_CPU0_PWR_VR
J 0
(-6025 4275);
DISPLAY 1.361702 (-6025 4275);
PAINT ORANGE (-6025 4275);
DISPLAY INVISIBLE (-6025 4275);
FORCEADD CAP_A..1
(-6350 4150);
FORCEPROP 1 LAST VOLTAGE 16V
J 0
(-6300 4150);
DISPLAY 0.617021 (-6300 4150);
PAINT SKYBLUE (-6300 4150);
FORCEPROP 1 LAST VALUE 0.1UF
J 0
(-6300 4200);
DISPLAY 0.617021 (-6300 4200);
PAINT SKYBLUE (-6300 4200);
FORCEPROP 1 LAST TOLERANCE 10%
J 0
(-6300 4100);
DISPLAY 0.617021 (-6300 4100);
PAINT SKYBLUE (-6300 4100);
FORCEPROP 1 LAST LOCATION C4D35
J 0
(-6300 4250);
DISPLAY 0.617021 (-6300 4250);
PAINT AQUA (-6300 4250);
FORCEPROP 1 LASTPIN (-6350 4250) $PN 1
J 0
(-6340 4230);
DISPLAY 0.617021 (-6340 4230);
PAINT ORANGE (-6340 4230);
FORCEPROP 1 LAST PACK_TYPE 0402V
J 0
(-6300 3950);
DISPLAY 0.617021 (-6300 3950);
PAINT SKYBLUE (-6300 3950);
FORCEPROP 1 LASTPIN (-6350 4050) $PN 2
J 0
(-6340 4030);
DISPLAY 0.617021 (-6340 4030);
PAINT ORANGE (-6340 4030);
FORCEPROP 1 LAST MATERIAL X7R
J 0
(-6300 4050);
DISPLAY 0.617021 (-6300 4050);
PAINT SKYBLUE (-6300 4050);
FORCEPROP 1 LAST PART_NUMBER A36096-030
J 0
(-6300 4000);
DISPLAY 0.617021 (-6300 4000);
PAINT BLUE (-6300 4000);
FORCEPROP 2 LAST SEC 1
J 0
(-6300 4350);
DISPLAY 0.680851 (-6300 4350);
PAINT MONO (-6300 4350);
DISPLAY INVISIBLE (-6300 4350);
FORCEPROP 2 LAST SEC_TYPE 0402V
J 0
(-6300 4350);
DISPLAY 1.021277 (-6300 4350);
PAINT ORANGE (-6300 4350);
DISPLAY INVISIBLE (-6300 4350);
FORCEPROP 2 LAST ROOM PVCCIN_CPU0_PWR_VR
J 0
(-6300 4300);
DISPLAY 1.361702 (-6300 4300);
PAINT ORANGE (-6300 4300);
DISPLAY INVISIBLE (-6300 4300);
FORCEPROP 2 LAST CDS_SEC 1
J 0
(-6300 4300);
PAINT ORANGE (-6300 4300);
DISPLAY INVISIBLE (-6300 4300);
FORCEPROP 2 LAST CDS_LOCATION C4D35
J 0
(-6300 4250);
DISPLAY 0.617021 (-6300 4250);
PAINT AQUA (-6300 4250);
DISPLAY INVISIBLE (-6300 4250);
FORCEPROP 1 LAST PATH I46
J 0
(-6300 4300);
DISPLAY 0.978723 (-6300 4300);
PAINT WHITE (-6300 4300);
DISPLAY INVISIBLE (-6300 4300);
FORCEPROP 2 LAST CDS_LIB dev_discrete
J 0
(-6350 4150);
PAINT ORANGE (-6350 4150);
DISPLAY INVISIBLE (-6350 4150);
FORCEADD CAP..1
(-6600 4150);
FORCEPROP 1 LAST LOCATION C4D30
J 0
(-6550 4250);
DISPLAY 0.617021 (-6550 4250);
PAINT AQUA (-6550 4250);
FORCEPROP 1 LAST VALUE 1.0UF
J 0
(-6550 4200);
DISPLAY 0.617021 (-6550 4200);
PAINT SKYBLUE (-6550 4200);
FORCEPROP 1 LAST TOLERANCE 10%
J 0
(-6550 4100);
DISPLAY 0.617021 (-6550 4100);
PAINT SKYBLUE (-6550 4100);
FORCEPROP 1 LAST VOLTAGE 16V
J 0
(-6550 4150);
DISPLAY 0.617021 (-6550 4150);
PAINT SKYBLUE (-6550 4150);
FORCEPROP 1 LASTPIN (-6600 4250) $PN 1
J 0
(-6590 4230);
DISPLAY 0.617021 (-6590 4230);
PAINT ORANGE (-6590 4230);
FORCEPROP 1 LAST PART_NUMBER D97712-011
J 0
(-6575 4000);
DISPLAY 0.617021 (-6575 4000);
PAINT BLUE (-6575 4000);
FORCEPROP 1 LAST PACK_TYPE 0402
J 0
(-6550 3950);
DISPLAY 0.617021 (-6550 3950);
PAINT SKYBLUE (-6550 3950);
FORCEPROP 1 LAST MATERIAL X6S
J 0
(-6550 4050);
DISPLAY 0.617021 (-6550 4050);
PAINT SKYBLUE (-6550 4050);
FORCEPROP 1 LASTPIN (-6600 4050) $PN 2
J 0
(-6590 4030);
DISPLAY 0.617021 (-6590 4030);
PAINT ORANGE (-6590 4030);
FORCEPROP 2 LAST ROOM PVCCIN_CPU0_PWR_VR
J 0
(-6550 4300);
DISPLAY 1.361702 (-6550 4300);
PAINT ORANGE (-6550 4300);
DISPLAY INVISIBLE (-6550 4300);
FORCEPROP 2 LAST SEC 1
J 0
(-6550 4350);
DISPLAY 0.680851 (-6550 4350);
PAINT MONO (-6550 4350);
DISPLAY INVISIBLE (-6550 4350);
FORCEPROP 2 LAST SEC_TYPE 0402
J 0
(-6550 4350);
DISPLAY 1.021277 (-6550 4350);
PAINT ORANGE (-6550 4350);
DISPLAY INVISIBLE (-6550 4350);
FORCEPROP 2 LAST CDS_LIB mstr_discrete
J 0
(-6600 4150);
PAINT ORANGE (-6600 4150);
DISPLAY INVISIBLE (-6600 4150);
FORCEPROP 2 LAST CDS_LOCATION C4D30
J 0
(-6550 4250);
DISPLAY 0.617021 (-6550 4250);
PAINT AQUA (-6550 4250);
DISPLAY INVISIBLE (-6550 4250);
FORCEPROP 1 LAST PATH I47
J 0
(-6550 4300);
DISPLAY 0.978723 (-6550 4300);
PAINT WHITE (-6550 4300);
DISPLAY INVISIBLE (-6550 4300);
FORCEADD CAP..1
(-5525 1475);
FORCEPROP 1 LAST PART_NUMBER A36096-155
J 0
(-5475 1325);
DISPLAY 0.617021 (-5475 1325);
PAINT BLUE (-5475 1325);
FORCEPROP 1 LAST LOCATION C4D5
J 0
(-5475 1575);
DISPLAY 0.617021 (-5475 1575);
PAINT AQUA (-5475 1575);
FORCEPROP 1 LASTPIN (-5525 1575) $PN 1
J 0
(-5515 1555);
DISPLAY 0.617021 (-5515 1555);
PAINT ORANGE (-5515 1555);
FORCEPROP 1 LAST VALUE 0.22UF
J 0
(-5475 1525);
DISPLAY 0.617021 (-5475 1525);
PAINT SKYBLUE (-5475 1525);
FORCEPROP 1 LAST PACK_TYPE 0402
J 0
(-5475 1275);
DISPLAY 0.617021 (-5475 1275);
PAINT SKYBLUE (-5475 1275);
FORCEPROP 1 LAST MATERIAL X7R
J 0
(-5475 1375);
DISPLAY 0.617021 (-5475 1375);
PAINT SKYBLUE (-5475 1375);
FORCEPROP 1 LAST VOLTAGE 16V
J 0
(-5475 1475);
DISPLAY 0.617021 (-5475 1475);
PAINT SKYBLUE (-5475 1475);
FORCEPROP 1 LAST TOLERANCE 10%
J 0
(-5475 1425);
DISPLAY 0.617021 (-5475 1425);
PAINT SKYBLUE (-5475 1425);
FORCEPROP 1 LASTPIN (-5525 1375) $PN 2
J 0
(-5515 1355);
DISPLAY 0.617021 (-5515 1355);
PAINT ORANGE (-5515 1355);
FORCEPROP 2 LAST SEC_TYPE 0402
J 0
(-5475 1675);
DISPLAY 1.021277 (-5475 1675);
PAINT ORANGE (-5475 1675);
DISPLAY INVISIBLE (-5475 1675);
FORCEPROP 2 LAST SEC 1
J 0
(-5475 1675);
DISPLAY 0.680851 (-5475 1675);
PAINT MONO (-5475 1675);
DISPLAY INVISIBLE (-5475 1675);
FORCEPROP 2 LAST CDS_LOCATION C4D5
J 0
(-5475 1575);
DISPLAY 0.617021 (-5475 1575);
PAINT AQUA (-5475 1575);
DISPLAY INVISIBLE (-5475 1575);
FORCEPROP 1 LAST PATH I48
J 0
(-5475 1625);
DISPLAY 0.978723 (-5475 1625);
PAINT WHITE (-5475 1625);
DISPLAY INVISIBLE (-5475 1625);
FORCEPROP 2 LAST ROOM PVCCIN_CPU0_PWR_VR
J 0
(-5475 1625);
DISPLAY 1.361702 (-5475 1625);
PAINT ORANGE (-5475 1625);
DISPLAY INVISIBLE (-5475 1625);
FORCEPROP 2 LAST CDS_LIB mstr_discrete
J 0
(-5525 1475);
PAINT ORANGE (-5525 1475);
DISPLAY INVISIBLE (-5525 1475);
FORCEADD CAP_A..1
R 2
(-5650 1475);
FORCEPROP 1 LAST TOLERANCE 10%
J 2
(-5700 1425);
DISPLAY 0.617021 (-5700 1425);
PAINT SKYBLUE (-5700 1425);
FORCEPROP 1 LAST LOCATION C4D6
J 2
(-5700 1575);
DISPLAY 0.617021 (-5700 1575);
PAINT AQUA (-5700 1575);
FORCEPROP 1 LASTPIN (-5650 1575) $PN 1
J 2
(-5660 1555);
DISPLAY 0.617021 (-5660 1555);
PAINT ORANGE (-5660 1555);
FORCEPROP 1 LAST VALUE 1.0UF
J 2
(-5700 1525);
DISPLAY 0.617021 (-5700 1525);
PAINT SKYBLUE (-5700 1525);
FORCEPROP 1 LAST VOLTAGE 6.3V
J 2
(-5700 1475);
DISPLAY 0.617021 (-5700 1475);
PAINT SKYBLUE (-5700 1475);
FORCEPROP 1 LAST MATERIAL X6S
J 2
(-5700 1375);
DISPLAY 0.617021 (-5700 1375);
PAINT SKYBLUE (-5700 1375);
FORCEPROP 1 LASTPIN (-5650 1375) $PN 2
J 2
(-5660 1355);
DISPLAY 0.617021 (-5660 1355);
PAINT ORANGE (-5660 1355);
FORCEPROP 1 LAST PACK_TYPE 0402V
J 2
(-5700 1275);
DISPLAY 0.617021 (-5700 1275);
PAINT SKYBLUE (-5700 1275);
FORCEPROP 1 LAST PART_NUMBER D97712-004
J 2
(-5700 1325);
DISPLAY 0.617021 (-5700 1325);
PAINT BLUE (-5700 1325);
FORCEPROP 2 LAST ROOM PVCCIN_CPU0_PWR_VR
J 0
(-5700 1625);
DISPLAY 1.361702 (-5700 1625);
PAINT ORANGE (-5700 1625);
DISPLAY INVISIBLE (-5700 1625);
FORCEPROP 1 LAST PATH I49
J 2
(-5700 1625);
DISPLAY 0.978723 (-5700 1625);
PAINT WHITE (-5700 1625);
DISPLAY INVISIBLE (-5700 1625);
FORCEPROP 2 LAST SEC 1
J 0
(-5700 1675);
DISPLAY 0.680851 (-5700 1675);
PAINT MONO (-5700 1675);
DISPLAY INVISIBLE (-5700 1675);
FORCEPROP 2 LAST SEC_TYPE 0402V
J 0
(-5700 1675);
DISPLAY 1.021277 (-5700 1675);
PAINT ORANGE (-5700 1675);
DISPLAY INVISIBLE (-5700 1675);
FORCEPROP 2 LAST CDS_SEC 1
J 0
(-5700 1625);
PAINT ORANGE (-5700 1625);
DISPLAY INVISIBLE (-5700 1625);
FORCEPROP 2 LAST CDS_LOCATION C4D6
J 2
(-5700 1575);
DISPLAY 0.617021 (-5700 1575);
PAINT AQUA (-5700 1575);
DISPLAY INVISIBLE (-5700 1575);
FORCEPROP 2 LAST CDS_LIB dev_discrete
J 0
(-5650 1475);
PAINT ORANGE (-5650 1475);
DISPLAY INVISIBLE (-5650 1475);
FORCEADD OFFPAGE..2
(-1100 4700);
FORCEPROP 2 LAST $XR0 201 
J 0
(-911 4700);
DISPLAY 0.638298 (-911 4700);
PAINT MONO (-911 4700);
FORCEPROP 1 LAST COMMENT_BODY TRUE
J 0
(-1145 4605);
DISPLAY 1.723404 (-1145 4605);
PAINT GREEN (-1145 4605);
DISPLAY INVISIBLE (-1145 4605);
FORCEPROP 1 LAST OFFPAGE TRUE
J 0
(-775 4575);
DISPLAY 1.723404 (-775 4575);
PAINT GREEN (-775 4575);
DISPLAY INVISIBLE (-775 4575);
FORCEPROP 2 LAST BOM_COST PROC_VRD_VCCIN_CPU0
J 0
(-900 4750);
DISPLAY 1.446809 (-900 4750);
PAINT MONO (-900 4750);
DISPLAY INVISIBLE (-900 4750);
FORCEPROP 2 LAST PATH I5
J 0
(-925 4775);
DISPLAY 1.021277 (-925 4775);
PAINT ORANGE (-925 4775);
DISPLAY INVISIBLE (-925 4775);
FORCEPROP 2 LAST CDS_LIB mstr_standard
J 2
(-1100 4700);
DISPLAY 1.936170 (-1100 4700);
PAINT ORANGE (-1100 4700);
DISPLAY INVISIBLE (-1100 4700);
FORCEPROP 2 LAST ROOM PVCCIN_CPU0_PWR_VR
J 0
(-1500 4775);
DISPLAY 1.936170 (-1500 4775);
PAINT ORANGE (-1500 4775);
DISPLAY INVISIBLE (-1500 4775);
FORCEADD RES..1
(-5900 1975);
FORCEPROP 1 LASTPIN (-5800 1975) $PN 2
J 0
(-5838 1987);
DISPLAY 0.617021 (-5838 1987);
PAINT ORANGE (-5838 1987);
FORCEPROP 1 LAST MATERIAL CHIP
J 0
(-5825 1800);
DISPLAY 0.617021 (-5825 1800);
PAINT SKYBLUE (-5825 1800);
FORCEPROP 1 LAST PACK_TYPE 0402
J 0
(-5850 1850);
DISPLAY 0.617021 (-5850 1850);
PAINT SKYBLUE (-5850 1850);
FORCEPROP 1 LAST PART_NUMBER G21796-090
J 0
(-6025 1900);
DISPLAY 0.617021 (-6025 1900);
PAINT BLUE (-6025 1900);
FORCEPROP 1 LAST WATTAGE 1/16W
J 2
(-5875 1800);
DISPLAY 0.617021 (-5875 1800);
PAINT SKYBLUE (-5875 1800);
FORCEPROP 1 LASTPIN (-6000 1975) $PN 1
J 0
(-5988 1987);
DISPLAY 0.617021 (-5988 1987);
PAINT ORANGE (-5988 1987);
FORCEPROP 1 LAST TOLERANCE 1%
J 0
(-5950 1850);
DISPLAY 0.617021 (-5950 1850);
PAINT SKYBLUE (-5950 1850);
FORCEPROP 1 LAST VALUE 1.0
J 2
(-6000 1850);
DISPLAY 0.617021 (-6000 1850);
PAINT SKYBLUE (-6000 1850);
FORCEPROP 1 LAST LOCATION R6P10
J 0
(-5950 2025);
DISPLAY 0.617021 (-5950 2025);
PAINT AQUA (-5950 2025);
FORCEPROP 2 LAST ROOM PVCCIN_CPU0_PWR_VR
J 0
(-5950 2075);
DISPLAY 1.361702 (-5950 2075);
PAINT ORANGE (-5950 2075);
DISPLAY INVISIBLE (-5950 2075);
FORCEPROP 1 LAST PATH I50
J 0
(-5950 2125);
DISPLAY 0.978723 (-5950 2125);
PAINT WHITE (-5950 2125);
DISPLAY INVISIBLE (-5950 2125);
FORCEPROP 2 LAST SEC 1
J 0
(-5950 2175);
DISPLAY 0.680851 (-5950 2175);
PAINT MONO (-5950 2175);
DISPLAY INVISIBLE (-5950 2175);
FORCEPROP 2 LAST SEC_TYPE 0402
J 0
(-5950 2175);
DISPLAY 1.021277 (-5950 2175);
PAINT ORANGE (-5950 2175);
DISPLAY INVISIBLE (-5950 2175);
FORCEPROP 2 LAST CDS_LOCATION R6P10
J 0
(-5950 2025);
DISPLAY 0.617021 (-5950 2025);
PAINT AQUA (-5950 2025);
DISPLAY INVISIBLE (-5950 2025);
FORCEPROP 2 LAST CDS_LIB mstr_discrete
J 0
(-5900 1975);
PAINT ORANGE (-5900 1975);
DISPLAY INVISIBLE (-5900 1975);
FORCEADD CAP..1
(-6225 1450);
FORCEPROP 1 LAST PART_NUMBER D97712-011
J 0
(-6175 1300);
DISPLAY 0.617021 (-6175 1300);
PAINT BLUE (-6175 1300);
FORCEPROP 1 LAST MATERIAL X6S
J 0
(-6175 1350);
DISPLAY 0.617021 (-6175 1350);
PAINT SKYBLUE (-6175 1350);
FORCEPROP 1 LAST LOCATION C4D7
J 0
(-6175 1550);
DISPLAY 0.617021 (-6175 1550);
PAINT AQUA (-6175 1550);
FORCEPROP 1 LAST VALUE 1.0UF
J 0
(-6175 1500);
DISPLAY 0.617021 (-6175 1500);
PAINT SKYBLUE (-6175 1500);
FORCEPROP 1 LAST TOLERANCE 10%
J 0
(-6175 1400);
DISPLAY 0.617021 (-6175 1400);
PAINT SKYBLUE (-6175 1400);
FORCEPROP 1 LAST PACK_TYPE 0402
J 0
(-6175 1250);
DISPLAY 0.617021 (-6175 1250);
PAINT SKYBLUE (-6175 1250);
FORCEPROP 1 LAST VOLTAGE 16V
J 0
(-6175 1450);
DISPLAY 0.617021 (-6175 1450);
PAINT SKYBLUE (-6175 1450);
FORCEPROP 1 LASTPIN (-6225 1550) $PN 1
J 0
(-6215 1530);
DISPLAY 0.617021 (-6215 1530);
PAINT ORANGE (-6215 1530);
FORCEPROP 1 LASTPIN (-6225 1350) $PN 2
J 0
(-6215 1330);
DISPLAY 0.617021 (-6215 1330);
PAINT ORANGE (-6215 1330);
FORCEPROP 2 LAST SEC_TYPE 0402
J 0
(-6175 1650);
DISPLAY 1.021277 (-6175 1650);
PAINT ORANGE (-6175 1650);
DISPLAY INVISIBLE (-6175 1650);
FORCEPROP 2 LAST SEC 1
J 0
(-6175 1650);
DISPLAY 0.680851 (-6175 1650);
PAINT MONO (-6175 1650);
DISPLAY INVISIBLE (-6175 1650);
FORCEPROP 2 LAST CDS_LOCATION C4D7
J 0
(-6175 1550);
DISPLAY 0.617021 (-6175 1550);
PAINT AQUA (-6175 1550);
DISPLAY INVISIBLE (-6175 1550);
FORCEPROP 1 LAST PATH I51
J 0
(-6175 1600);
DISPLAY 0.978723 (-6175 1600);
PAINT WHITE (-6175 1600);
DISPLAY INVISIBLE (-6175 1600);
FORCEPROP 2 LAST ROOM PVCCIN_CPU0_PWR_VR
J 0
(-6175 1600);
DISPLAY 1.361702 (-6175 1600);
PAINT ORANGE (-6175 1600);
DISPLAY INVISIBLE (-6175 1600);
FORCEPROP 2 LAST CDS_LIB mstr_discrete
J 0
(-6225 1450);
PAINT ORANGE (-6225 1450);
DISPLAY INVISIBLE (-6225 1450);
FORCEADD CAP_A..1
(-6475 1450);
FORCEPROP 1 LAST VOLTAGE 16V
J 0
(-6425 1450);
DISPLAY 0.617021 (-6425 1450);
PAINT SKYBLUE (-6425 1450);
FORCEPROP 1 LAST LOCATION C4D11
J 0
(-6425 1550);
DISPLAY 0.617021 (-6425 1550);
PAINT AQUA (-6425 1550);
FORCEPROP 1 LAST VALUE 0.1UF
J 0
(-6425 1500);
DISPLAY 0.617021 (-6425 1500);
PAINT SKYBLUE (-6425 1500);
FORCEPROP 1 LAST PART_NUMBER A36096-030
J 0
(-6425 1300);
DISPLAY 0.617021 (-6425 1300);
PAINT BLUE (-6425 1300);
FORCEPROP 1 LASTPIN (-6475 1550) $PN 1
J 0
(-6465 1530);
DISPLAY 0.617021 (-6465 1530);
PAINT ORANGE (-6465 1530);
FORCEPROP 1 LAST TOLERANCE 10%
J 0
(-6425 1400);
DISPLAY 0.617021 (-6425 1400);
PAINT SKYBLUE (-6425 1400);
FORCEPROP 1 LAST PACK_TYPE 0402V
J 0
(-6425 1250);
DISPLAY 0.617021 (-6425 1250);
PAINT SKYBLUE (-6425 1250);
FORCEPROP 1 LAST MATERIAL X7R
J 0
(-6425 1350);
DISPLAY 0.617021 (-6425 1350);
PAINT SKYBLUE (-6425 1350);
FORCEPROP 1 LASTPIN (-6475 1350) $PN 2
J 0
(-6465 1330);
DISPLAY 0.617021 (-6465 1330);
PAINT ORANGE (-6465 1330);
FORCEPROP 2 LAST SEC 1
J 0
(-6425 1650);
DISPLAY 0.680851 (-6425 1650);
PAINT MONO (-6425 1650);
DISPLAY INVISIBLE (-6425 1650);
FORCEPROP 2 LAST SEC_TYPE 0402V
J 0
(-6425 1650);
DISPLAY 1.021277 (-6425 1650);
PAINT ORANGE (-6425 1650);
DISPLAY INVISIBLE (-6425 1650);
FORCEPROP 2 LAST CDS_SEC 1
J 0
(-6425 1600);
PAINT ORANGE (-6425 1600);
DISPLAY INVISIBLE (-6425 1600);
FORCEPROP 2 LAST CDS_LOCATION C4D11
J 0
(-6425 1550);
DISPLAY 0.617021 (-6425 1550);
PAINT AQUA (-6425 1550);
DISPLAY INVISIBLE (-6425 1550);
FORCEPROP 2 LAST ROOM PVCCIN_CPU0_PWR_VR
J 0
(-6425 1600);
DISPLAY 1.361702 (-6425 1600);
PAINT ORANGE (-6425 1600);
DISPLAY INVISIBLE (-6425 1600);
FORCEPROP 1 LAST PATH I52
J 0
(-6425 1600);
DISPLAY 0.978723 (-6425 1600);
PAINT WHITE (-6425 1600);
DISPLAY INVISIBLE (-6425 1600);
FORCEPROP 2 LAST CDS_LIB dev_discrete
J 0
(-6475 1450);
PAINT ORANGE (-6475 1450);
DISPLAY INVISIBLE (-6475 1450);
FORCEADD CAP..1
(-6700 1400);
FORCEPROP 1 LAST LOCATION C4D10
J 0
(-6650 1500);
DISPLAY 0.617021 (-6650 1500);
PAINT AQUA (-6650 1500);
FORCEPROP 1 LAST PART_NUMBER D97712-011
J 0
(-6650 1250);
DISPLAY 0.617021 (-6650 1250);
PAINT BLUE (-6650 1250);
FORCEPROP 1 LAST VALUE 1.0UF
J 0
(-6650 1450);
DISPLAY 0.617021 (-6650 1450);
PAINT SKYBLUE (-6650 1450);
FORCEPROP 1 LAST VOLTAGE 16V
J 0
(-6650 1400);
DISPLAY 0.617021 (-6650 1400);
PAINT SKYBLUE (-6650 1400);
FORCEPROP 1 LAST MATERIAL X6S
J 0
(-6650 1300);
DISPLAY 0.617021 (-6650 1300);
PAINT SKYBLUE (-6650 1300);
FORCEPROP 1 LAST TOLERANCE 10%
J 0
(-6650 1350);
DISPLAY 0.617021 (-6650 1350);
PAINT SKYBLUE (-6650 1350);
FORCEPROP 1 LAST PACK_TYPE 0402
J 0
(-6650 1200);
DISPLAY 0.617021 (-6650 1200);
PAINT SKYBLUE (-6650 1200);
FORCEPROP 1 LASTPIN (-6700 1500) $PN 1
J 0
(-6690 1480);
DISPLAY 0.617021 (-6690 1480);
PAINT ORANGE (-6690 1480);
FORCEPROP 1 LASTPIN (-6700 1300) $PN 2
J 0
(-6690 1280);
DISPLAY 0.617021 (-6690 1280);
PAINT ORANGE (-6690 1280);
FORCEPROP 2 LAST ROOM PVCCIN_CPU0_PWR_VR
J 0
(-6650 1550);
DISPLAY 1.361702 (-6650 1550);
PAINT ORANGE (-6650 1550);
DISPLAY INVISIBLE (-6650 1550);
FORCEPROP 1 LAST PATH I53
J 0
(-6650 1550);
DISPLAY 0.978723 (-6650 1550);
PAINT WHITE (-6650 1550);
DISPLAY INVISIBLE (-6650 1550);
FORCEPROP 2 LAST SEC 1
J 0
(-6650 1600);
DISPLAY 0.680851 (-6650 1600);
PAINT MONO (-6650 1600);
DISPLAY INVISIBLE (-6650 1600);
FORCEPROP 2 LAST SEC_TYPE 0402
J 0
(-6650 1600);
DISPLAY 1.021277 (-6650 1600);
PAINT ORANGE (-6650 1600);
DISPLAY INVISIBLE (-6650 1600);
FORCEPROP 2 LAST CDS_LOCATION C4D10
J 0
(-6650 1500);
DISPLAY 0.617021 (-6650 1500);
PAINT AQUA (-6650 1500);
DISPLAY INVISIBLE (-6650 1500);
FORCEPROP 2 LAST CDS_LIB mstr_discrete
J 0
(-6700 1400);
PAINT ORANGE (-6700 1400);
DISPLAY INVISIBLE (-6700 1400);
FORCEADD CAP..1
(-7425 4150);
FORCEPROP 1 LAST LOCATION C6P19
J 0
(-7375 4250);
DISPLAY 0.617021 (-7375 4250);
PAINT AQUA (-7375 4250);
FORCEPROP 1 LAST VALUE 10UF
J 0
(-7375 4200);
DISPLAY 0.617021 (-7375 4200);
PAINT SKYBLUE (-7375 4200);
FORCEPROP 1 LAST TOLERANCE 10%
J 0
(-7375 4100);
DISPLAY 0.617021 (-7375 4100);
PAINT SKYBLUE (-7375 4100);
FORCEPROP 1 LAST VOLTAGE 16V
J 0
(-7375 4150);
DISPLAY 0.617021 (-7375 4150);
PAINT SKYBLUE (-7375 4150);
FORCEPROP 1 LASTPIN (-7425 4250) $PN 1
J 0
(-7415 4230);
DISPLAY 0.617021 (-7415 4230);
PAINT ORANGE (-7415 4230);
FORCEPROP 1 LAST PART_NUMBER C95333-007
J 0
(-7375 4000);
DISPLAY 0.617021 (-7375 4000);
PAINT BLUE (-7375 4000);
FORCEPROP 1 LAST PACK_TYPE 0805
J 0
(-7375 3950);
DISPLAY 0.617021 (-7375 3950);
PAINT SKYBLUE (-7375 3950);
FORCEPROP 1 LAST MATERIAL X6S
J 0
(-7375 4050);
DISPLAY 0.617021 (-7375 4050);
PAINT SKYBLUE (-7375 4050);
FORCEPROP 1 LASTPIN (-7425 4050) $PN 2
J 0
(-7415 4030);
DISPLAY 0.617021 (-7415 4030);
PAINT ORANGE (-7415 4030);
FORCEPROP 1 LAST PATH I54
J 0
(-7375 4300);
DISPLAY 0.978723 (-7375 4300);
PAINT WHITE (-7375 4300);
DISPLAY INVISIBLE (-7375 4300);
FORCEPROP 2 LAST ROOM PVCCIN_CPU0_PWR_VR
J 0
(-7375 4300);
DISPLAY 1.361702 (-7375 4300);
PAINT ORANGE (-7375 4300);
DISPLAY INVISIBLE (-7375 4300);
FORCEPROP 2 LAST CDS_LOCATION C6P19
J 0
(-7375 4250);
DISPLAY 0.617021 (-7375 4250);
PAINT AQUA (-7375 4250);
DISPLAY INVISIBLE (-7375 4250);
FORCEPROP 2 LAST SEC 1
J 0
(-7375 4350);
DISPLAY 0.680851 (-7375 4350);
PAINT MONO (-7375 4350);
DISPLAY INVISIBLE (-7375 4350);
FORCEPROP 2 LAST SEC_TYPE 0805
J 0
(-7375 4350);
DISPLAY 1.021277 (-7375 4350);
PAINT ORANGE (-7375 4350);
DISPLAY INVISIBLE (-7375 4350);
FORCEPROP 2 LAST CDS_LIB mstr_discrete
J 0
(-7425 4150);
PAINT ORANGE (-7425 4150);
DISPLAY INVISIBLE (-7425 4150);
FORCEADD OFFPAGE..1
(-6800 3800);
FORCEPROP 2 LASTPIN (-6750 3800) SIG_NAME VR_PVCCIN_CPU0_PWM3
J 0
(-6735 3810);
DISPLAY 0.617021 (-6735 3810);
PAINT ORANGE (-6735 3810);
FORCEPROP 2 LAST $XR0 201 
J 0
(-7052 3800);
DISPLAY 0.638298 (-7052 3800);
PAINT MONO (-7052 3800);
FORCEPROP 1 LAST COMMENT_BODY TRUE
J 0
(-6675 3700);
DISPLAY 1.680851 (-6675 3700);
PAINT GREEN (-6675 3700);
DISPLAY INVISIBLE (-6675 3700);
FORCEPROP 1 LAST OFFPAGE TRUE
J 0
(-6475 3675);
DISPLAY 1.680851 (-6475 3675);
PAINT GREEN (-6475 3675);
DISPLAY INVISIBLE (-6475 3675);
FORCEPROP 2 LAST PATH I55
J 0
(-6750 3875);
DISPLAY 1.021277 (-6750 3875);
PAINT ORANGE (-6750 3875);
DISPLAY INVISIBLE (-6750 3875);
FORCEPROP 2 LAST CDS_LIB mstr_standard
J 0
(-6800 3800);
DISPLAY 1.936170 (-6800 3800);
PAINT ORANGE (-6800 3800);
DISPLAY INVISIBLE (-6800 3800);
FORCEPROP 2 LAST BOM_COST PROC_VRD_VCCIN_CPU0
J 0
(-7050 3850);
DISPLAY 1.446809 (-7050 3850);
PAINT MONO (-7050 3850);
DISPLAY INVISIBLE (-7050 3850);
FORCEPROP 2 LAST ROOM PVCCIN_CPU0_PWR_VR
J 0
(-7200 3875);
DISPLAY 1.936170 (-7200 3875);
PAINT ORANGE (-7200 3875);
DISPLAY INVISIBLE (-7200 3875);
FORCEADD GND..1
(-7425 3750);
FORCEPROP 3 LASTPIN (-7425 3800) SIG_NAME GND\g
J 0
(-7415 3810);
DISPLAY 0.659574 (-7415 3810);
PAINT MONO (-7415 3810);
DISPLAY INVISIBLE (-7415 3810);
FORCEPROP 1 LAST HDL_POWER GND
J 0
(-7425 3900);
DISPLAY 1.723404 (-7425 3900);
PAINT GREEN (-7425 3900);
DISPLAY INVISIBLE (-7425 3900);
FORCEPROP 1 LAST BODY_TYPE PLUMBING
J 0
(-7470 3707);
DISPLAY 0.340426 (-7470 3707);
PAINT GREEN (-7470 3707);
DISPLAY INVISIBLE (-7470 3707);
FORCEPROP 1 LAST PATH I56
J 0
(-7350 3750);
DISPLAY 0.872340 (-7350 3750);
PAINT AQUA (-7350 3750);
DISPLAY INVISIBLE (-7350 3750);
FORCEPROP 1 LAST SIZE 1B
J 0
(-7350 3700);
DISPLAY 1.723404 (-7350 3700);
PAINT GREEN (-7350 3700);
DISPLAY INVISIBLE (-7350 3700);
FORCEPROP 2 LAST CDS_LIB mstr_symbols
J 0
(-7425 3750);
DISPLAY 1.936170 (-7425 3750);
PAINT ORANGE (-7425 3750);
DISPLAY INVISIBLE (-7425 3750);
FORCEPROP 1 LAST VOLTAGE 0
J 0
(-7425 3750);
PAINT SKYBLUE (-7425 3750);
DISPLAY INVISIBLE (-7425 3750);
FORCEPROP 2 LAST BOM_COST PROC_VRD_VCCIN_CPU0
J 0
(-7800 3825);
DISPLAY 1.446809 (-7800 3825);
PAINT MONO (-7800 3825);
DISPLAY INVISIBLE (-7800 3825);
FORCEPROP 2 LAST ROOM PVCCIN_CPU0_PWR_VR
J 0
(-7975 3825);
DISPLAY 1.936170 (-7975 3825);
PAINT ORANGE (-7975 3825);
DISPLAY INVISIBLE (-7975 3825);
FORCEADD CAP..1
(-6950 1400);
FORCEPROP 1 LAST PART_NUMBER C95333-007
J 0
(-6900 1250);
DISPLAY 0.617021 (-6900 1250);
PAINT BLUE (-6900 1250);
FORCEPROP 1 LAST VALUE 10UF
J 0
(-6900 1450);
DISPLAY 0.617021 (-6900 1450);
PAINT SKYBLUE (-6900 1450);
FORCEPROP 1 LAST LOCATION C6P20
J 0
(-6900 1500);
DISPLAY 0.617021 (-6900 1500);
PAINT AQUA (-6900 1500);
FORCEPROP 1 LAST MATERIAL X6S
J 0
(-6900 1300);
DISPLAY 0.617021 (-6900 1300);
PAINT SKYBLUE (-6900 1300);
FORCEPROP 1 LAST VOLTAGE 16V
J 0
(-6900 1400);
DISPLAY 0.617021 (-6900 1400);
PAINT SKYBLUE (-6900 1400);
FORCEPROP 1 LAST TOLERANCE 10%
J 0
(-6900 1350);
DISPLAY 0.617021 (-6900 1350);
PAINT SKYBLUE (-6900 1350);
FORCEPROP 1 LAST PACK_TYPE 0805
J 0
(-6900 1200);
DISPLAY 0.617021 (-6900 1200);
PAINT SKYBLUE (-6900 1200);
FORCEPROP 1 LASTPIN (-6950 1300) $PN 2
J 0
(-6940 1280);
DISPLAY 0.617021 (-6940 1280);
PAINT ORANGE (-6940 1280);
FORCEPROP 1 LASTPIN (-6950 1500) $PN 1
J 0
(-6940 1480);
DISPLAY 0.617021 (-6940 1480);
PAINT ORANGE (-6940 1480);
FORCEPROP 2 LAST ROOM PVCCIN_CPU0_PWR_VR
J 0
(-6900 1550);
DISPLAY 1.361702 (-6900 1550);
PAINT ORANGE (-6900 1550);
DISPLAY INVISIBLE (-6900 1550);
FORCEPROP 1 LAST PATH I57
J 0
(-6900 1550);
DISPLAY 0.978723 (-6900 1550);
PAINT WHITE (-6900 1550);
DISPLAY INVISIBLE (-6900 1550);
FORCEPROP 2 LAST SEC 1
J 0
(-6900 1600);
DISPLAY 0.680851 (-6900 1600);
PAINT MONO (-6900 1600);
DISPLAY INVISIBLE (-6900 1600);
FORCEPROP 2 LAST SEC_TYPE 0805
J 0
(-6900 1600);
DISPLAY 1.021277 (-6900 1600);
PAINT ORANGE (-6900 1600);
DISPLAY INVISIBLE (-6900 1600);
FORCEPROP 2 LAST CDS_LOCATION C6P20
J 0
(-6900 1500);
DISPLAY 0.617021 (-6900 1500);
PAINT AQUA (-6900 1500);
DISPLAY INVISIBLE (-6900 1500);
FORCEPROP 2 LAST CDS_LIB mstr_discrete
J 0
(-6950 1400);
PAINT ORANGE (-6950 1400);
DISPLAY INVISIBLE (-6950 1400);
FORCEADD CAP..1
(-7200 1450);
FORCEPROP 1 LAST LOCATION C6P15
J 0
(-7150 1550);
DISPLAY 0.617021 (-7150 1550);
PAINT AQUA (-7150 1550);
FORCEPROP 1 LAST PART_NUMBER C95333-007
J 0
(-7150 1300);
DISPLAY 0.617021 (-7150 1300);
PAINT BLUE (-7150 1300);
FORCEPROP 1 LAST MATERIAL X6S
J 0
(-7150 1350);
DISPLAY 0.617021 (-7150 1350);
PAINT SKYBLUE (-7150 1350);
FORCEPROP 1 LAST VOLTAGE 16V
J 0
(-7150 1450);
DISPLAY 0.617021 (-7150 1450);
PAINT SKYBLUE (-7150 1450);
FORCEPROP 1 LAST TOLERANCE 10%
J 0
(-7150 1400);
DISPLAY 0.617021 (-7150 1400);
PAINT SKYBLUE (-7150 1400);
FORCEPROP 1 LAST VALUE 10UF
J 0
(-7150 1500);
DISPLAY 0.617021 (-7150 1500);
PAINT SKYBLUE (-7150 1500);
FORCEPROP 1 LAST PACK_TYPE 0805
J 0
(-7150 1250);
DISPLAY 0.617021 (-7150 1250);
PAINT SKYBLUE (-7150 1250);
FORCEPROP 1 LASTPIN (-7200 1350) $PN 2
J 0
(-7190 1330);
DISPLAY 0.617021 (-7190 1330);
PAINT ORANGE (-7190 1330);
FORCEPROP 1 LASTPIN (-7200 1550) $PN 1
J 0
(-7190 1530);
DISPLAY 0.617021 (-7190 1530);
PAINT ORANGE (-7190 1530);
FORCEPROP 2 LAST ROOM PVCCIN_CPU0_PWR_VR
J 0
(-7150 1600);
DISPLAY 1.361702 (-7150 1600);
PAINT ORANGE (-7150 1600);
DISPLAY INVISIBLE (-7150 1600);
FORCEPROP 1 LAST PATH I58
J 0
(-7150 1600);
DISPLAY 0.978723 (-7150 1600);
PAINT WHITE (-7150 1600);
DISPLAY INVISIBLE (-7150 1600);
FORCEPROP 2 LAST CDS_LOCATION C6P15
J 0
(-7150 1550);
DISPLAY 0.617021 (-7150 1550);
PAINT AQUA (-7150 1550);
DISPLAY INVISIBLE (-7150 1550);
FORCEPROP 2 LAST SEC 1
J 0
(-7150 1650);
DISPLAY 0.680851 (-7150 1650);
PAINT MONO (-7150 1650);
DISPLAY INVISIBLE (-7150 1650);
FORCEPROP 2 LAST SEC_TYPE 0805
J 0
(-7150 1650);
DISPLAY 1.021277 (-7150 1650);
PAINT ORANGE (-7150 1650);
DISPLAY INVISIBLE (-7150 1650);
FORCEPROP 2 LAST CDS_LIB mstr_discrete
J 0
(-7200 1450);
PAINT ORANGE (-7200 1450);
DISPLAY INVISIBLE (-7200 1450);
FORCEADD CAP..1
(-7475 1450);
FORCEPROP 1 LAST PART_NUMBER C95333-007
J 0
(-7425 1300);
DISPLAY 0.617021 (-7425 1300);
PAINT BLUE (-7425 1300);
FORCEPROP 1 LAST LOCATION C6P7
J 0
(-7425 1550);
DISPLAY 0.617021 (-7425 1550);
PAINT AQUA (-7425 1550);
FORCEPROP 1 LASTPIN (-7475 1550) $PN 1
J 0
(-7465 1530);
DISPLAY 0.617021 (-7465 1530);
PAINT ORANGE (-7465 1530);
FORCEPROP 1 LAST VALUE 10UF
J 0
(-7425 1500);
DISPLAY 0.617021 (-7425 1500);
PAINT SKYBLUE (-7425 1500);
FORCEPROP 1 LAST TOLERANCE 10%
J 0
(-7425 1400);
DISPLAY 0.617021 (-7425 1400);
PAINT SKYBLUE (-7425 1400);
FORCEPROP 1 LAST PACK_TYPE 0805
J 0
(-7425 1250);
DISPLAY 0.617021 (-7425 1250);
PAINT SKYBLUE (-7425 1250);
FORCEPROP 1 LAST VOLTAGE 16V
J 0
(-7425 1450);
DISPLAY 0.617021 (-7425 1450);
PAINT SKYBLUE (-7425 1450);
FORCEPROP 1 LAST MATERIAL X6S
J 0
(-7425 1350);
DISPLAY 0.617021 (-7425 1350);
PAINT SKYBLUE (-7425 1350);
FORCEPROP 1 LASTPIN (-7475 1350) $PN 2
J 0
(-7465 1330);
DISPLAY 0.617021 (-7465 1330);
PAINT ORANGE (-7465 1330);
FORCEPROP 1 LAST PATH I59
J 0
(-7425 1600);
DISPLAY 0.978723 (-7425 1600);
PAINT WHITE (-7425 1600);
DISPLAY INVISIBLE (-7425 1600);
FORCEPROP 2 LAST ROOM PVCCIN_CPU0_PWR_VR
J 0
(-7425 1600);
DISPLAY 1.361702 (-7425 1600);
PAINT ORANGE (-7425 1600);
DISPLAY INVISIBLE (-7425 1600);
FORCEPROP 2 LAST CDS_LOCATION C6P7
J 0
(-7425 1550);
DISPLAY 0.617021 (-7425 1550);
PAINT AQUA (-7425 1550);
DISPLAY INVISIBLE (-7425 1550);
FORCEPROP 2 LAST SEC 1
J 0
(-7425 1650);
DISPLAY 0.680851 (-7425 1650);
PAINT MONO (-7425 1650);
DISPLAY INVISIBLE (-7425 1650);
FORCEPROP 2 LAST SEC_TYPE 0805
J 0
(-7425 1650);
DISPLAY 1.021277 (-7425 1650);
PAINT ORANGE (-7425 1650);
DISPLAY INVISIBLE (-7425 1650);
FORCEPROP 2 LAST CDS_LIB mstr_discrete
J 0
(-7475 1450);
PAINT ORANGE (-7475 1450);
DISPLAY INVISIBLE (-7475 1450);
FORCEADD OFFPAGE..2
(-1000 4450);
FORCEPROP 2 LAST $XR0 201 
J 0
(-811 4450);
DISPLAY 0.638298 (-811 4450);
PAINT MONO (-811 4450);
FORCEPROP 1 LAST COMMENT_BODY TRUE
J 0
(-1045 4355);
DISPLAY 1.723404 (-1045 4355);
PAINT GREEN (-1045 4355);
DISPLAY INVISIBLE (-1045 4355);
FORCEPROP 1 LAST OFFPAGE TRUE
J 0
(-675 4325);
DISPLAY 1.723404 (-675 4325);
PAINT GREEN (-675 4325);
DISPLAY INVISIBLE (-675 4325);
FORCEPROP 2 LAST BOM_COST PROC_VRD_VCCIN_CPU0
J 0
(-800 4500);
DISPLAY 1.446809 (-800 4500);
PAINT MONO (-800 4500);
DISPLAY INVISIBLE (-800 4500);
FORCEPROP 2 LAST PATH I6
J 0
(-825 4525);
DISPLAY 1.021277 (-825 4525);
PAINT ORANGE (-825 4525);
DISPLAY INVISIBLE (-825 4525);
FORCEPROP 2 LAST CDS_LIB mstr_standard
J 0
(-1000 4450);
DISPLAY 1.936170 (-1000 4450);
PAINT ORANGE (-1000 4450);
DISPLAY INVISIBLE (-1000 4450);
FORCEPROP 2 LAST ROOM PVCCIN_CPU0_PWR_VR
J 0
(-1400 4525);
DISPLAY 1.936170 (-1400 4525);
PAINT ORANGE (-1400 4525);
DISPLAY INVISIBLE (-1400 4525);
FORCEADD OFFPAGE..1
(-6775 1075);
FORCEPROP 2 LAST $XR0 201 
J 0
(-7027 1075);
DISPLAY 0.638298 (-7027 1075);
PAINT MONO (-7027 1075);
FORCEPROP 1 LAST COMMENT_BODY TRUE
J 0
(-6650 975);
DISPLAY 1.680851 (-6650 975);
PAINT GREEN (-6650 975);
DISPLAY INVISIBLE (-6650 975);
FORCEPROP 1 LAST OFFPAGE TRUE
J 0
(-6450 950);
DISPLAY 1.680851 (-6450 950);
PAINT GREEN (-6450 950);
DISPLAY INVISIBLE (-6450 950);
FORCEPROP 2 LAST PATH I60
J 0
(-6725 1150);
DISPLAY 1.021277 (-6725 1150);
PAINT ORANGE (-6725 1150);
DISPLAY INVISIBLE (-6725 1150);
FORCEPROP 2 LAST CDS_LIB mstr_standard
J 0
(-6775 1075);
PAINT ORANGE (-6775 1075);
DISPLAY INVISIBLE (-6775 1075);
FORCEPROP 2 LAST BOM_COST PROC_VRD_VCCIN_CPU0
J 0
(-7025 1125);
DISPLAY 1.446809 (-7025 1125);
PAINT MONO (-7025 1125);
DISPLAY INVISIBLE (-7025 1125);
FORCEPROP 2 LAST ROOM PVCCIN_CPU0_PWR_VR
J 0
(-7175 1150);
DISPLAY 1.936170 (-7175 1150);
PAINT ORANGE (-7175 1150);
DISPLAY INVISIBLE (-7175 1150);
FORCEADD VCC_CORE..1
(-7475 1900);
FORCEPROP 3 LASTPIN (-7475 1850) SIG_NAME VR_FET_SW_P12V_STBY_PVCCIN_CPU0\g
J 0
(-7465 1860);
DISPLAY 0.659574 (-7465 1860);
PAINT MONO (-7465 1860);
DISPLAY INVISIBLE (-7465 1860);
FORCEPROP 1 LAST HDL_POWER VR_FET_SW_P12V_STBY_PVCCIN_CPU0
J 1
(-7450 1950);
DISPLAY 0.617021 (-7450 1950);
PAINT GREEN (-7450 1950);
FORCEPROP 2 LAST CDS_LIB mstr_symbols
J 0
(-7475 1900);
PAINT ORANGE (-7475 1900);
DISPLAY INVISIBLE (-7475 1900);
FORCEPROP 1 LAST PATH I61
J 0
(-7425 1925);
DISPLAY 0.872340 (-7425 1925);
PAINT AQUA (-7425 1925);
DISPLAY INVISIBLE (-7425 1925);
FORCEADD GND..1
(-7475 1025);
FORCEPROP 3 LASTPIN (-7475 1075) SIG_NAME GND\g
J 0
(-7465 1085);
DISPLAY 0.659574 (-7465 1085);
PAINT MONO (-7465 1085);
DISPLAY INVISIBLE (-7465 1085);
FORCEPROP 1 LAST HDL_POWER GND
J 0
(-7475 1175);
DISPLAY 1.723404 (-7475 1175);
PAINT GREEN (-7475 1175);
DISPLAY INVISIBLE (-7475 1175);
FORCEPROP 1 LAST BODY_TYPE PLUMBING
J 0
(-7520 982);
DISPLAY 0.340426 (-7520 982);
PAINT GREEN (-7520 982);
DISPLAY INVISIBLE (-7520 982);
FORCEPROP 1 LAST PATH I62
J 0
(-7400 1025);
DISPLAY 0.872340 (-7400 1025);
PAINT AQUA (-7400 1025);
DISPLAY INVISIBLE (-7400 1025);
FORCEPROP 1 LAST VOLTAGE 0
J 0
(-7475 1025);
PAINT SKYBLUE (-7475 1025);
DISPLAY INVISIBLE (-7475 1025);
FORCEPROP 2 LAST CDS_LIB mstr_symbols
J 0
(-7475 1025);
PAINT ORANGE (-7475 1025);
DISPLAY INVISIBLE (-7475 1025);
FORCEPROP 2 LAST BOM_COST PROC_VRD_VCCIN_CPU0
J 0
(-7850 1100);
DISPLAY 1.446809 (-7850 1100);
PAINT MONO (-7850 1100);
DISPLAY INVISIBLE (-7850 1100);
FORCEPROP 2 LAST ROOM PVCCIN_CPU0_PWR_VR
J 0
(-8025 1100);
DISPLAY 1.936170 (-8025 1100);
PAINT ORANGE (-8025 1100);
DISPLAY INVISIBLE (-8025 1100);
FORCEPROP 1 LAST SIZE 1B
J 0
(-7400 975);
DISPLAY 1.723404 (-7400 975);
PAINT GREEN (-7400 975);
DISPLAY INVISIBLE (-7400 975);
FORCEADD GND..1
(-2775 500);
FORCEPROP 3 LASTPIN (-2775 550) SIG_NAME GND\g
J 0
(-2765 560);
DISPLAY 0.659574 (-2765 560);
PAINT MONO (-2765 560);
DISPLAY INVISIBLE (-2765 560);
FORCEPROP 1 LAST HDL_POWER GND
J 0
(-2775 650);
DISPLAY 1.723404 (-2775 650);
PAINT GREEN (-2775 650);
DISPLAY INVISIBLE (-2775 650);
FORCEPROP 1 LAST BODY_TYPE PLUMBING
J 0
(-2820 457);
DISPLAY 0.340426 (-2820 457);
PAINT GREEN (-2820 457);
DISPLAY INVISIBLE (-2820 457);
FORCEPROP 1 LAST VOLTAGE 0
J 0
(-2775 500);
PAINT SKYBLUE (-2775 500);
DISPLAY INVISIBLE (-2775 500);
FORCEPROP 2 LAST CDS_LIB mstr_symbols
J 0
(-2775 500);
PAINT ORANGE (-2775 500);
DISPLAY INVISIBLE (-2775 500);
FORCEPROP 1 LAST SIZE 1B
J 0
(-2700 450);
DISPLAY 1.723404 (-2700 450);
PAINT GREEN (-2700 450);
DISPLAY INVISIBLE (-2700 450);
FORCEPROP 1 LAST PATH I63
J 0
(-2700 500);
DISPLAY 0.872340 (-2700 500);
PAINT AQUA (-2700 500);
DISPLAY INVISIBLE (-2700 500);
FORCEPROP 2 LAST BOM_COST PROC_VRD_VCCIN_CPU0
J 0
(-3150 575);
DISPLAY 1.446809 (-3150 575);
PAINT MONO (-3150 575);
DISPLAY INVISIBLE (-3150 575);
FORCEPROP 2 LAST ROOM PVCCIN_CPU0_PWR_VR
J 0
(-3325 575);
DISPLAY 1.936170 (-3325 575);
PAINT ORANGE (-3325 575);
DISPLAY INVISIBLE (-3325 575);
FORCEADD P5V_STBY..1
(-4625 4850);
FORCEPROP 3 LASTPIN (-4625 4800) SIG_NAME P5V_STBY\g
J 0
(-4615 4810);
DISPLAY 0.659574 (-4615 4810);
PAINT MONO (-4615 4810);
DISPLAY INVISIBLE (-4615 4810);
FORCEPROP 1 LAST HDL_POWER P5V_STBY
J 0
(-4925 4725);
DISPLAY 0.872340 (-4925 4725);
PAINT ORANGE (-4925 4725);
DISPLAY INVISIBLE (-4925 4725);
FORCEPROP 1 LAST BODY_TYPE PLUMBING
J 0
(-4670 4807);
DISPLAY 0.340426 (-4670 4807);
PAINT GREEN (-4670 4807);
DISPLAY INVISIBLE (-4670 4807);
FORCEPROP 1 LAST SIZE 1B
J 0
(-4580 4872);
DISPLAY 0.340426 (-4580 4872);
PAINT GREEN (-4580 4872);
DISPLAY INVISIBLE (-4580 4872);
FORCEPROP 1 LAST PATH I64
J 0
(-4580 4852);
DISPLAY 0.340426 (-4580 4852);
PAINT GREEN (-4580 4852);
DISPLAY INVISIBLE (-4580 4852);
FORCEPROP 2 LAST CDS_LIB mstr_symbols
J 0
(-4625 4850);
PAINT ORANGE (-4625 4850);
DISPLAY INVISIBLE (-4625 4850);
FORCEPROP 1 LAST VOLTAGE 5.0V
J 0
(-4670 4807);
DISPLAY 0.340426 (-4670 4807);
PAINT SKYBLUE (-4670 4807);
DISPLAY INVISIBLE (-4670 4807);
FORCEADD P5V_STBY..1
(-4600 2100);
FORCEPROP 3 LASTPIN (-4600 2050) SIG_NAME P5V_STBY\g
J 0
(-4590 2060);
DISPLAY 0.659574 (-4590 2060);
PAINT MONO (-4590 2060);
DISPLAY INVISIBLE (-4590 2060);
FORCEPROP 1 LAST HDL_POWER P5V_STBY
J 0
(-4900 1975);
DISPLAY 0.872340 (-4900 1975);
PAINT ORANGE (-4900 1975);
DISPLAY INVISIBLE (-4900 1975);
FORCEPROP 1 LAST BODY_TYPE PLUMBING
J 0
(-4645 2057);
DISPLAY 0.340426 (-4645 2057);
PAINT GREEN (-4645 2057);
DISPLAY INVISIBLE (-4645 2057);
FORCEPROP 1 LAST VOLTAGE 5.0V
J 0
(-4645 2057);
DISPLAY 0.340426 (-4645 2057);
PAINT SKYBLUE (-4645 2057);
DISPLAY INVISIBLE (-4645 2057);
FORCEPROP 2 LAST CDS_LIB mstr_symbols
J 0
(-4600 2100);
PAINT ORANGE (-4600 2100);
DISPLAY INVISIBLE (-4600 2100);
FORCEPROP 1 LAST SIZE 1B
J 0
(-4555 2122);
DISPLAY 0.340426 (-4555 2122);
PAINT GREEN (-4555 2122);
DISPLAY INVISIBLE (-4555 2122);
FORCEPROP 1 LAST PATH I65
J 0
(-4555 2102);
DISPLAY 0.340426 (-4555 2102);
PAINT GREEN (-4555 2102);
DISPLAY INVISIBLE (-4555 2102);
FORCEADD CAP_A..1
(-1025 3375);
FORCEPROP 1 LAST PART_NUMBER E15431-004
J 0
(-975 3225);
DISPLAY 0.617021 (-975 3225);
PAINT BLUE (-975 3225);
FORCEPROP 1 LAST LOCATION C6P21
J 0
(-975 3475);
DISPLAY 0.617021 (-975 3475);
PAINT AQUA (-975 3475);
FORCEPROP 1 LAST VALUE 22.0UF
J 0
(-975 3425);
DISPLAY 0.617021 (-975 3425);
PAINT SKYBLUE (-975 3425);
FORCEPROP 1 LAST TOLERANCE 20%
J 0
(-975 3325);
DISPLAY 0.617021 (-975 3325);
PAINT SKYBLUE (-975 3325);
FORCEPROP 1 LAST PACK_TYPE 0603V
J 0
(-975 3175);
DISPLAY 0.617021 (-975 3175);
PAINT SKYBLUE (-975 3175);
FORCEPROP 1 LAST VOLTAGE 4V
J 0
(-975 3375);
DISPLAY 0.617021 (-975 3375);
PAINT SKYBLUE (-975 3375);
FORCEPROP 1 LAST MATERIAL X6S
J 0
(-975 3275);
DISPLAY 0.617021 (-975 3275);
PAINT SKYBLUE (-975 3275);
FORCEPROP 1 LASTPIN (-1025 3475) $PN 1
J 0
(-1015 3455);
DISPLAY 0.617021 (-1015 3455);
PAINT ORANGE (-1015 3455);
FORCEPROP 1 LASTPIN (-1025 3275) $PN 2
J 0
(-1015 3255);
DISPLAY 0.617021 (-1015 3255);
PAINT ORANGE (-1015 3255);
FORCEPROP 0 LAST BOM_COST PROC_VRD_VCCIN_CPU0
J 0
(-975 3575);
DISPLAY 1.021277 (-975 3575);
PAINT ORANGE (-975 3575);
DISPLAY INVISIBLE (-975 3575);
FORCEPROP 2 LAST SEC_TYPE 0603V
J 0
(-975 3575);
DISPLAY 1.021277 (-975 3575);
PAINT ORANGE (-975 3575);
DISPLAY INVISIBLE (-975 3575);
FORCEPROP 2 LAST SEC 1
J 0
(-975 3575);
DISPLAY 0.680851 (-975 3575);
PAINT MONO (-975 3575);
DISPLAY INVISIBLE (-975 3575);
FORCEPROP 0 LAST ROOM PVCCIN_CPU0_PWR_VR
J 0
(-975 3575);
DISPLAY 1.021277 (-975 3575);
PAINT ORANGE (-975 3575);
DISPLAY INVISIBLE (-975 3575);
FORCEPROP 2 LAST CDS_LOCATION C6P21
J 0
(-975 3475);
DISPLAY 0.617021 (-975 3475);
PAINT AQUA (-975 3475);
DISPLAY INVISIBLE (-975 3475);
FORCEPROP 2 LAST CDS_SEC 1
J 0
(-975 3525);
PAINT ORANGE (-975 3525);
DISPLAY INVISIBLE (-975 3525);
FORCEPROP 1 LAST PATH I66
J 0
(-975 3525);
DISPLAY 0.978723 (-975 3525);
PAINT WHITE (-975 3525);
DISPLAY INVISIBLE (-975 3525);
FORCEPROP 2 LAST CDS_LIB dev_discrete
J 0
(-1025 3375);
PAINT ORANGE (-1025 3375);
DISPLAY INVISIBLE (-1025 3375);
FORCEADD RES..2
(-700 2525);
FORCEPROP 1 LAST LOCATION R4E13
J 0
(-655 2650);
DISPLAY 0.617021 (-655 2650);
PAINT AQUA (-655 2650);
FORCEPROP 1 LAST PART_NUMBER G22026-038
J 0
(-660 2400);
DISPLAY 0.617021 (-660 2400);
PAINT BLUE (-660 2400);
FORCEPROP 1 LAST VALUE 100.0
J 0
(-655 2600);
DISPLAY 0.617021 (-655 2600);
PAINT SKYBLUE (-655 2600);
FORCEPROP 1 LASTPIN (-700 2625) $PN 1
J 0
(-695 2587);
DISPLAY 0.617021 (-695 2587);
PAINT ORANGE (-695 2587);
FORCEPROP 1 LAST TOLERANCE 1%
J 0
(-655 2550);
DISPLAY 0.617021 (-655 2550);
PAINT SKYBLUE (-655 2550);
FORCEPROP 1 LAST WATTAGE 1/10W
J 0
(-660 2500);
DISPLAY 0.617021 (-660 2500);
PAINT SKYBLUE (-660 2500);
FORCEPROP 1 LAST MATERIAL CHIP
J 0
(-660 2450);
DISPLAY 0.617021 (-660 2450);
PAINT SKYBLUE (-660 2450);
FORCEPROP 1 LAST PACK_TYPE 0603
J 0
(-660 2350);
DISPLAY 0.617021 (-660 2350);
PAINT SKYBLUE (-660 2350);
FORCEPROP 1 LASTPIN (-700 2425) $PN 2
J 0
(-695 2435);
DISPLAY 0.617021 (-695 2435);
PAINT ORANGE (-695 2435);
FORCEPROP 2 LAST SEC_TYPE 0603
J 0
(-650 2750);
DISPLAY 1.021277 (-650 2750);
PAINT ORANGE (-650 2750);
DISPLAY INVISIBLE (-650 2750);
FORCEPROP 0 LAST BOM_COST PROC_VRD_VCCIN_CPU0
J 0
(-650 2750);
DISPLAY 1.021277 (-650 2750);
PAINT ORANGE (-650 2750);
DISPLAY INVISIBLE (-650 2750);
FORCEPROP 2 LAST SEC 1
J 0
(-650 2750);
DISPLAY 0.680851 (-650 2750);
PAINT MONO (-650 2750);
DISPLAY INVISIBLE (-650 2750);
FORCEPROP 2 LAST CDS_LOCATION R4E13
J 0
(-655 2650);
DISPLAY 0.617021 (-655 2650);
PAINT AQUA (-655 2650);
DISPLAY INVISIBLE (-655 2650);
FORCEPROP 1 LAST PATH I67
J 0
(-650 2700);
DISPLAY 0.978723 (-650 2700);
PAINT WHITE (-650 2700);
DISPLAY INVISIBLE (-650 2700);
FORCEPROP 0 LAST ROOM PVCCIN_CPU0_DECAP_VR
J 0
(-650 2750);
DISPLAY 1.021277 (-650 2750);
PAINT ORANGE (-650 2750);
DISPLAY INVISIBLE (-650 2750);
FORCEPROP 2 LAST CDS_LIB mstr_discrete
J 0
(-700 2525);
PAINT ORANGE (-700 2525);
DISPLAY INVISIBLE (-700 2525);
FORCEADD CAP_A..1
(-750 3375);
FORCEPROP 1 LAST VALUE 22.0UF
J 0
(-700 3425);
DISPLAY 0.617021 (-700 3425);
PAINT SKYBLUE (-700 3425);
FORCEPROP 1 LAST PART_NUMBER E15431-004
J 0
(-700 3225);
DISPLAY 0.617021 (-700 3225);
PAINT BLUE (-700 3225);
FORCEPROP 1 LAST LOCATION C4D34
J 0
(-700 3475);
DISPLAY 0.617021 (-700 3475);
PAINT AQUA (-700 3475);
FORCEPROP 1 LAST VOLTAGE 4V
J 0
(-700 3375);
DISPLAY 0.617021 (-700 3375);
PAINT SKYBLUE (-700 3375);
FORCEPROP 1 LASTPIN (-750 3475) $PN 1
J 0
(-740 3455);
DISPLAY 0.617021 (-740 3455);
PAINT ORANGE (-740 3455);
FORCEPROP 1 LAST TOLERANCE 20%
J 0
(-700 3325);
DISPLAY 0.617021 (-700 3325);
PAINT SKYBLUE (-700 3325);
FORCEPROP 1 LASTPIN (-750 3275) $PN 2
J 0
(-740 3255);
DISPLAY 0.617021 (-740 3255);
PAINT ORANGE (-740 3255);
FORCEPROP 1 LAST MATERIAL X6S
J 0
(-700 3275);
DISPLAY 0.617021 (-700 3275);
PAINT SKYBLUE (-700 3275);
FORCEPROP 1 LAST PACK_TYPE 0603V
J 0
(-700 3175);
DISPLAY 0.617021 (-700 3175);
PAINT SKYBLUE (-700 3175);
FORCEPROP 2 LAST SEC_TYPE 0603V
J 0
(-700 3575);
DISPLAY 1.021277 (-700 3575);
PAINT ORANGE (-700 3575);
DISPLAY INVISIBLE (-700 3575);
FORCEPROP 2 LAST SEC 1
J 0
(-700 3575);
DISPLAY 0.680851 (-700 3575);
PAINT MONO (-700 3575);
DISPLAY INVISIBLE (-700 3575);
FORCEPROP 2 LAST CDS_LOCATION C4D34
J 0
(-700 3475);
DISPLAY 0.617021 (-700 3475);
PAINT AQUA (-700 3475);
DISPLAY INVISIBLE (-700 3475);
FORCEPROP 2 LAST CDS_LIB dev_discrete
J 0
(-750 3375);
PAINT ORANGE (-750 3375);
DISPLAY INVISIBLE (-750 3375);
FORCEPROP 2 LAST CDS_SEC 1
J 0
(-700 3525);
PAINT ORANGE (-700 3525);
DISPLAY INVISIBLE (-700 3525);
FORCEPROP 1 LAST PATH I68
J 0
(-700 3525);
DISPLAY 0.978723 (-700 3525);
PAINT WHITE (-700 3525);
DISPLAY INVISIBLE (-700 3525);
FORCEADD CAP_A..1
(-750 575);
FORCEPROP 1 LAST VOLTAGE 4V
J 0
(-700 575);
DISPLAY 0.617021 (-700 575);
PAINT SKYBLUE (-700 575);
FORCEPROP 1 LAST VALUE 22.0UF
J 0
(-700 625);
DISPLAY 0.617021 (-700 625);
PAINT SKYBLUE (-700 625);
FORCEPROP 1 LAST LOCATION C4D4
J 0
(-700 675);
DISPLAY 0.617021 (-700 675);
PAINT AQUA (-700 675);
FORCEPROP 1 LAST MATERIAL X6S
J 0
(-700 475);
DISPLAY 0.617021 (-700 475);
PAINT SKYBLUE (-700 475);
FORCEPROP 1 LAST PART_NUMBER E15431-004
J 0
(-700 425);
DISPLAY 0.617021 (-700 425);
PAINT BLUE (-700 425);
FORCEPROP 1 LASTPIN (-750 675) $PN 1
J 0
(-740 655);
DISPLAY 0.617021 (-740 655);
PAINT ORANGE (-740 655);
FORCEPROP 1 LAST TOLERANCE 20%
J 0
(-700 525);
DISPLAY 0.617021 (-700 525);
PAINT SKYBLUE (-700 525);
FORCEPROP 1 LASTPIN (-750 475) $PN 2
J 0
(-740 455);
DISPLAY 0.617021 (-740 455);
PAINT ORANGE (-740 455);
FORCEPROP 1 LAST PACK_TYPE 0603V
J 0
(-700 375);
DISPLAY 0.617021 (-700 375);
PAINT SKYBLUE (-700 375);
FORCEPROP 2 LAST SEC 1
J 0
(-700 775);
DISPLAY 0.680851 (-700 775);
PAINT MONO (-700 775);
DISPLAY INVISIBLE (-700 775);
FORCEPROP 2 LAST SEC_TYPE 0603V
J 0
(-700 775);
DISPLAY 1.021277 (-700 775);
PAINT ORANGE (-700 775);
DISPLAY INVISIBLE (-700 775);
FORCEPROP 1 LAST PATH I69
J 0
(-700 725);
DISPLAY 0.978723 (-700 725);
PAINT WHITE (-700 725);
DISPLAY INVISIBLE (-700 725);
FORCEPROP 2 LAST CDS_LOCATION C4D4
J 0
(-700 675);
DISPLAY 0.617021 (-700 675);
PAINT AQUA (-700 675);
DISPLAY INVISIBLE (-700 675);
FORCEPROP 2 LAST CDS_LIB dev_discrete
J 0
(-750 575);
PAINT ORANGE (-750 575);
DISPLAY INVISIBLE (-750 575);
FORCEPROP 2 LAST CDS_SEC 1
J 0
(-700 725);
PAINT ORANGE (-700 725);
DISPLAY INVISIBLE (-700 725);
FORCEADD OFFPAGE..2
(-1700 4075);
FORCEPROP 2 LAST $XR0 202 
J 0
(-1511 4075);
DISPLAY 0.638298 (-1511 4075);
PAINT MONO (-1511 4075);
FORCEPROP 2 LAST $XR1 203 
J 0
(-1391 4075);
DISPLAY 0.638298 (-1391 4075);
PAINT MONO (-1391 4075);
FORCEPROP 2 LAST $XR3 201 
J 0
(-1151 4075);
DISPLAY 0.638298 (-1151 4075);
PAINT MONO (-1151 4075);
FORCEPROP 2 LAST $XR2 204 
J 0
(-1271 4075);
DISPLAY 0.638298 (-1271 4075);
PAINT MONO (-1271 4075);
FORCEPROP 1 LAST COMMENT_BODY TRUE
J 0
(-1745 3980);
DISPLAY 1.723404 (-1745 3980);
PAINT GREEN (-1745 3980);
DISPLAY INVISIBLE (-1745 3980);
FORCEPROP 1 LAST OFFPAGE TRUE
J 0
(-1375 3950);
DISPLAY 1.723404 (-1375 3950);
PAINT GREEN (-1375 3950);
DISPLAY INVISIBLE (-1375 3950);
FORCEPROP 2 LAST CDS_LIB mstr_standard
J 0
(-1700 4075);
PAINT ORANGE (-1700 4075);
DISPLAY INVISIBLE (-1700 4075);
FORCEPROP 2 LAST PATH I7
J 0
(-1525 4150);
DISPLAY 1.021277 (-1525 4150);
PAINT ORANGE (-1525 4150);
DISPLAY INVISIBLE (-1525 4150);
FORCEPROP 2 LAST BOM_COST PROC_VRD_VCCIN_CPU0
J 0
(-1500 4125);
DISPLAY 1.446809 (-1500 4125);
PAINT MONO (-1500 4125);
DISPLAY INVISIBLE (-1500 4125);
FORCEPROP 2 LAST ROOM PVCCIN_CPU0_PWR_VR
J 0
(-2100 4150);
DISPLAY 1.936170 (-2100 4150);
PAINT ORANGE (-2100 4150);
DISPLAY INVISIBLE (-2100 4150);
FORCEADD IR354XX..1
(-3325 3900);
FORCEPROP 2 LASTPIN (-3825 4350) $PN 25
J 2
(-3835 4360);
DISPLAY 0.617021 (-3835 4360);
PAINT MONO (-3835 4360);
FORCEPROP 2 LASTPIN (-2825 3950) $PN 36
J 0
(-2815 3960);
DISPLAY 0.617021 (-2815 3960);
PAINT MONO (-2815 3960);
FORCEPROP 2 LASTPIN (-3825 3700) $PN 39
J 2
(-3835 3710);
DISPLAY 0.617021 (-3835 3710);
PAINT MONO (-3835 3710);
FORCEPROP 2 LASTPIN (-2825 4250) $PN 37
J 0
(-2815 4260);
DISPLAY 0.617021 (-2815 4260);
PAINT MONO (-2815 4260);
FORCEPROP 2 LASTPIN (-2825 4200) $PN 31
J 0
(-2815 4210);
DISPLAY 0.617021 (-2815 4210);
PAINT MONO (-2815 4210);
FORCEPROP 2 LASTPIN (-2825 4450) $PN 38
J 0
(-2815 4460);
DISPLAY 0.617021 (-2815 4460);
PAINT MONO (-2815 4460);
FORCEPROP 1 LAST VALUE IR35411
J 1
(-3325 4525);
DISPLAY 0.617021 (-3325 4525);
PAINT SKYBLUE (-3325 4525);
FORCEPROP 1 LAST LOCATION EU4D3
J 0
(-3775 4700);
DISPLAY 0.617021 (-3775 4700);
PAINT AQUA (-3775 4700);
FORCEPROP 1 LAST MATERIAL IC
J 0
(-3775 4650);
DISPLAY 0.617021 (-3775 4650);
PAINT SKYBLUE (-3775 4650);
FORCEPROP 2 LASTPIN (-3825 4400) $PN 30
J 2
(-3835 4410);
DISPLAY 0.617021 (-3835 4410);
PAINT MONO (-3835 4410);
FORCEPROP 2 LASTPIN (-3825 4250) $PN 4
J 2
(-3835 4260);
DISPLAY 0.617021 (-3835 4260);
PAINT MONO (-3835 4260);
FORCEPROP 2 LASTPIN (-3825 4450) $PN 3
J 2
(-3835 4460);
DISPLAY 0.617021 (-3835 4460);
PAINT MONO (-3835 4460);
FORCEPROP 2 LASTPIN (-3825 4150) $PN 35
J 2
(-3835 4160);
DISPLAY 0.617021 (-3835 4160);
PAINT MONO (-3835 4160);
FORCEPROP 2 LASTPIN (-2825 3600) $PN 10
J 0
(-2815 3610);
DISPLAY 0.617021 (-2815 3610);
PAINT MONO (-2815 3610);
FORCEPROP 2 LASTPIN (-2825 3500) $PN 2
J 0
(-2815 3510);
DISPLAY 0.617021 (-2815 3510);
PAINT MONO (-2815 3510);
FORCEPROP 2 LASTPIN (-2825 3450) $PN 40
J 0
(-2815 3460);
DISPLAY 0.617021 (-2815 3460);
PAINT MONO (-2815 3460);
FORCEPROP 2 LASTPIN (-2825 3400) $PN 7
J 0
(-2815 3410);
DISPLAY 0.617021 (-2815 3410);
PAINT MONO (-2815 3410);
FORCEPROP 2 LASTPIN (-2825 3350) $PN 5
J 0
(-2815 3360);
DISPLAY 0.617021 (-2815 3360);
PAINT MONO (-2815 3360);
FORCEPROP 1 LAST PART_NUMBER H73688-001
J 0
(-3775 3200);
DISPLAY 0.617021 (-3775 3200);
PAINT BLUE (-3775 3200);
FORCEPROP 2 LASTPIN (-3825 3950) $PN 41
J 2
(-3835 3960);
DISPLAY 0.617021 (-3835 3960);
PAINT MONO (-3835 3960);
FORCEPROP 2 LASTPIN (-3825 3800) $PN 34
J 2
(-3835 3810);
DISPLAY 0.617021 (-3835 3810);
PAINT MONO (-3835 3810);
FORCEPROP 2 LASTPIN (-3825 4050) $PN 1
J 2
(-3835 4060);
DISPLAY 0.617021 (-3835 4060);
PAINT MONO (-3835 4060);
FORCEPROP 2 LASTPIN (-3825 3900) $PN 6
J 2
(-3835 3910);
DISPLAY 0.617021 (-3835 3910);
PAINT MONO (-3835 3910);
FORCEPROP 2 LASTPIN (-3825 3600) $PN 33
J 2
(-3835 3610);
DISPLAY 0.617021 (-3835 3610);
PAINT MONO (-3835 3610);
FORCEPROP 2 LASTPIN (-3825 3550) $PN 32
J 2
(-3835 3560);
DISPLAY 0.617021 (-3835 3560);
PAINT MONO (-3835 3560);
FORCEPROP 1 LAST PATH I70
J 0
(-3325 4650);
PAINT GREEN (-3325 4650);
DISPLAY INVISIBLE (-3325 4650);
FORCEPROP 1 LAST PACK_TYPE SM
J 0
(-3775 4750);
PAINT SKYBLUE (-3775 4750);
DISPLAY INVISIBLE (-3775 4750);
FORCEPROP 2 LAST SEC_TYPE SM
J 0
(-3775 4750);
DISPLAY 1.021277 (-3775 4750);
PAINT ORANGE (-3775 4750);
DISPLAY INVISIBLE (-3775 4750);
FORCEPROP 2 LAST SEC 1
J 0
(-3775 4750);
PAINT MONO (-3775 4750);
DISPLAY INVISIBLE (-3775 4750);
FORCEPROP 2 LAST CDS_LOCATION EU4D3
J 0
(-3775 4700);
PAINT GREEN (-3775 4700);
DISPLAY INVISIBLE (-3775 4700);
FORCEPROP 2 LAST CDS_LIB mstr_discrete
J 0
(-3325 3900);
PAINT ORANGE (-3325 3900);
DISPLAY INVISIBLE (-3325 3900);
FORCEADD IR354XX..1
(-3350 1175);
FORCEPROP 1 LAST PART_NUMBER H73688-001
J 0
(-3775 475);
DISPLAY 0.617021 (-3775 475);
PAINT BLUE (-3775 475);
FORCEPROP 2 LASTPIN (-2850 1475) $PN 31
J 0
(-2840 1485);
DISPLAY 0.617021 (-2840 1485);
PAINT MONO (-2840 1485);
FORCEPROP 1 LAST VALUE IR35411
J 1
(-3350 1800);
DISPLAY 0.617021 (-3350 1800);
PAINT SKYBLUE (-3350 1800);
FORCEPROP 2 LASTPIN (-3850 975) $PN 39
J 2
(-3860 985);
DISPLAY 0.617021 (-3860 985);
PAINT MONO (-3860 985);
FORCEPROP 2 LASTPIN (-3850 825) $PN 32
J 2
(-3860 835);
DISPLAY 0.617021 (-3860 835);
PAINT MONO (-3860 835);
FORCEPROP 2 LASTPIN (-3850 875) $PN 33
J 2
(-3860 885);
DISPLAY 0.617021 (-3860 885);
PAINT MONO (-3860 885);
FORCEPROP 2 LASTPIN (-3850 1075) $PN 34
J 2
(-3860 1085);
DISPLAY 0.617021 (-3860 1085);
PAINT MONO (-3860 1085);
FORCEPROP 2 LASTPIN (-3850 1175) $PN 6
J 2
(-3860 1185);
DISPLAY 0.617021 (-3860 1185);
PAINT MONO (-3860 1185);
FORCEPROP 2 LASTPIN (-3850 1425) $PN 35
J 2
(-3860 1435);
DISPLAY 0.617021 (-3860 1435);
PAINT MONO (-3860 1435);
FORCEPROP 2 LASTPIN (-3850 1525) $PN 4
J 2
(-3860 1535);
DISPLAY 0.617021 (-3860 1535);
PAINT MONO (-3860 1535);
FORCEPROP 2 LASTPIN (-3850 1675) $PN 30
J 2
(-3860 1685);
DISPLAY 0.617021 (-3860 1685);
PAINT MONO (-3860 1685);
FORCEPROP 2 LASTPIN (-3850 1625) $PN 25
J 2
(-3860 1635);
DISPLAY 0.617021 (-3860 1635);
PAINT MONO (-3860 1635);
FORCEPROP 2 LASTPIN (-3850 1725) $PN 3
J 2
(-3860 1735);
DISPLAY 0.617021 (-3860 1735);
PAINT MONO (-3860 1735);
FORCEPROP 1 LAST LOCATION EU4D1
J 0
(-3800 1975);
DISPLAY 0.617021 (-3800 1975);
PAINT AQUA (-3800 1975);
FORCEPROP 1 LAST MATERIAL IC
J 0
(-3800 1925);
DISPLAY 0.617021 (-3800 1925);
PAINT SKYBLUE (-3800 1925);
FORCEPROP 2 LASTPIN (-2850 625) $PN 5
J 0
(-2840 635);
DISPLAY 0.617021 (-2840 635);
PAINT MONO (-2840 635);
FORCEPROP 2 LASTPIN (-2850 675) $PN 7
J 0
(-2840 685);
DISPLAY 0.617021 (-2840 685);
PAINT MONO (-2840 685);
FORCEPROP 2 LASTPIN (-2850 725) $PN 40
J 0
(-2840 735);
DISPLAY 0.617021 (-2840 735);
PAINT MONO (-2840 735);
FORCEPROP 2 LASTPIN (-2850 875) $PN 10
J 0
(-2840 885);
DISPLAY 0.617021 (-2840 885);
PAINT MONO (-2840 885);
FORCEPROP 2 LASTPIN (-2850 1225) $PN 36
J 0
(-2840 1235);
DISPLAY 0.617021 (-2840 1235);
PAINT MONO (-2840 1235);
FORCEPROP 2 LASTPIN (-2850 1725) $PN 38
J 0
(-2840 1735);
DISPLAY 0.617021 (-2840 1735);
PAINT MONO (-2840 1735);
FORCEPROP 2 LASTPIN (-2850 1525) $PN 37
J 0
(-2840 1535);
DISPLAY 0.617021 (-2840 1535);
PAINT MONO (-2840 1535);
FORCEPROP 2 LASTPIN (-3850 1225) $PN 41
J 2
(-3860 1235);
DISPLAY 0.617021 (-3860 1235);
PAINT MONO (-3860 1235);
FORCEPROP 2 LASTPIN (-3850 1325) $PN 1
J 2
(-3860 1335);
DISPLAY 0.617021 (-3860 1335);
PAINT MONO (-3860 1335);
FORCEPROP 2 LASTPIN (-2850 775) $PN 2
J 0
(-2840 785);
DISPLAY 0.617021 (-2840 785);
PAINT MONO (-2840 785);
FORCEPROP 2 LAST CDS_LOCATION EU4D1
J 0
(-3800 1975);
PAINT GREEN (-3800 1975);
DISPLAY INVISIBLE (-3800 1975);
FORCEPROP 1 LAST PATH I71
J 0
(-3350 1925);
PAINT GREEN (-3350 1925);
DISPLAY INVISIBLE (-3350 1925);
FORCEPROP 2 LAST CDS_LIB mstr_discrete
J 0
(-3350 1175);
PAINT ORANGE (-3350 1175);
DISPLAY INVISIBLE (-3350 1175);
FORCEPROP 2 LAST $SEC 1
J 0
(-3800 2025);
PAINT MONO (-3800 2025);
DISPLAY INVISIBLE (-3800 2025);
FORCEPROP 2 LAST CDS_SEC 1
J 0
(-3800 2025);
PAINT MONO (-3800 2025);
DISPLAY INVISIBLE (-3800 2025);
FORCEPROP 1 LAST PACK_TYPE SM
J 0
(-3800 2025);
PAINT SKYBLUE (-3800 2025);
DISPLAY INVISIBLE (-3800 2025);
FORCEADD RES..2
(-625 4075);
FORCEPROP 1 LAST LOCATION R4D72
J 0
(-580 4200);
DISPLAY 0.617021 (-580 4200);
PAINT AQUA (-580 4200);
FORCEPROP 1 LAST VALUE 68.1K
J 0
(-580 4150);
DISPLAY 0.617021 (-580 4150);
PAINT SKYBLUE (-580 4150);
FORCEPROP 1 LAST TOLERANCE 1%
J 0
(-580 4100);
DISPLAY 0.617021 (-580 4100);
PAINT SKYBLUE (-580 4100);
FORCEPROP 1 LAST MATERIAL EMPTY
J 0
(-585 4000);
DISPLAY 0.617021 (-585 4000);
PAINT RED (-585 4000);
FORCEPROP 1 LAST PART_NUMBER G21796-187
J 0
(-585 3950);
DISPLAY 0.617021 (-585 3950);
PAINT BLUE (-585 3950);
FORCEPROP 1 LAST PACK_TYPE 0402
J 0
(-585 3900);
DISPLAY 0.617021 (-585 3900);
PAINT SKYBLUE (-585 3900);
FORCEPROP 1 LAST WATTAGE 1/16W
J 0
(-585 4050);
DISPLAY 0.617021 (-585 4050);
PAINT SKYBLUE (-585 4050);
FORCEPROP 2 LAST CDS_SEC 1
J 0
(-575 4300);
PAINT MONO (-575 4300);
DISPLAY INVISIBLE (-575 4300);
FORCEPROP 2 LAST $SEC 1
J 0
(-575 4300);
PAINT MONO (-575 4300);
DISPLAY INVISIBLE (-575 4300);
FORCEPROP 1 LAST PATH I89
J 0
(-575 4250);
DISPLAY 0.978723 (-575 4250);
PAINT WHITE (-575 4250);
DISPLAY INVISIBLE (-575 4250);
FORCEPROP 1 LASTPIN (-625 4175) $PN 1
J 0
(-620 4137);
DISPLAY 0.787234 (-620 4137);
PAINT ORANGE (-620 4137);
DISPLAY INVISIBLE (-620 4137);
FORCEPROP 2 LAST CDS_LIB mstr_discrete
J 0
(-625 4075);
PAINT ORANGE (-625 4075);
DISPLAY INVISIBLE (-625 4075);
FORCEPROP 1 LASTPIN (-625 3975) $PN 2
J 0
(-620 3985);
DISPLAY 0.787234 (-620 3985);
PAINT ORANGE (-620 3985);
DISPLAY INVISIBLE (-620 3985);
FORCEADD GND..1
(-625 3850);
FORCEPROP 3 LASTPIN (-625 3900) SIG_NAME GND\g
J 0
(-615 3910);
DISPLAY 0.659574 (-615 3910);
PAINT MONO (-615 3910);
DISPLAY INVISIBLE (-615 3910);
FORCEPROP 1 LAST HDL_POWER GND
J 0
(-625 4000);
DISPLAY 1.723404 (-625 4000);
PAINT GREEN (-625 4000);
DISPLAY INVISIBLE (-625 4000);
FORCEPROP 1 LAST BODY_TYPE PLUMBING
J 0
(-670 3807);
DISPLAY 0.340426 (-670 3807);
PAINT GREEN (-670 3807);
DISPLAY INVISIBLE (-670 3807);
FORCEPROP 1 LAST VOLTAGE 0
J 0
(-625 3850);
PAINT SKYBLUE (-625 3850);
DISPLAY INVISIBLE (-625 3850);
FORCEPROP 2 LAST CDS_LIB mstr_symbols
J 0
(-625 3850);
PAINT ORANGE (-625 3850);
DISPLAY INVISIBLE (-625 3850);
FORCEPROP 1 LAST PATH I90
J 0
(-550 3850);
DISPLAY 0.872340 (-550 3850);
PAINT AQUA (-550 3850);
DISPLAY INVISIBLE (-550 3850);
FORCEPROP 1 LAST SIZE 1B
J 0
(-550 3800);
DISPLAY 1.723404 (-550 3800);
PAINT GREEN (-550 3800);
DISPLAY INVISIBLE (-550 3800);
FORCEPROP 2 LAST BOM_COST PROC_VRD_VCCIN_CPU0
J 0
(-1000 3925);
DISPLAY 1.446809 (-1000 3925);
PAINT MONO (-1000 3925);
DISPLAY INVISIBLE (-1000 3925);
FORCEPROP 2 LAST ROOM PVCCIN_CPU0_PWR_VR
J 0
(-1175 3925);
DISPLAY 1.936170 (-1175 3925);
PAINT ORANGE (-1175 3925);
DISPLAY INVISIBLE (-1175 3925);
FORCEADD RES..2
(-450 1375);
FORCEPROP 1 LAST PART_NUMBER G21796-187
J 0
(-410 1250);
DISPLAY 0.617021 (-410 1250);
PAINT BLUE (-410 1250);
FORCEPROP 1 LAST MATERIAL EMPTY
J 0
(-410 1300);
DISPLAY 0.617021 (-410 1300);
PAINT RED (-410 1300);
FORCEPROP 1 LAST LOCATION R4D71
J 0
(-405 1500);
DISPLAY 0.617021 (-405 1500);
PAINT AQUA (-405 1500);
FORCEPROP 1 LAST VALUE 68.1K
J 0
(-405 1450);
DISPLAY 0.617021 (-405 1450);
PAINT SKYBLUE (-405 1450);
FORCEPROP 1 LAST TOLERANCE 1%
J 0
(-405 1400);
DISPLAY 0.617021 (-405 1400);
PAINT SKYBLUE (-405 1400);
FORCEPROP 1 LAST WATTAGE 1/16W
J 0
(-410 1350);
DISPLAY 0.617021 (-410 1350);
PAINT SKYBLUE (-410 1350);
FORCEPROP 1 LAST PACK_TYPE 0402
J 0
(-410 1200);
DISPLAY 0.617021 (-410 1200);
PAINT SKYBLUE (-410 1200);
FORCEPROP 2 LAST CDS_SEC 1
J 0
(-400 1600);
PAINT MONO (-400 1600);
DISPLAY INVISIBLE (-400 1600);
FORCEPROP 2 LAST $SEC 1
J 0
(-400 1600);
PAINT MONO (-400 1600);
DISPLAY INVISIBLE (-400 1600);
FORCEPROP 1 LAST PATH I91
J 0
(-400 1550);
DISPLAY 0.978723 (-400 1550);
PAINT WHITE (-400 1550);
DISPLAY INVISIBLE (-400 1550);
FORCEPROP 1 LASTPIN (-450 1475) $PN 1
J 0
(-445 1437);
DISPLAY 0.787234 (-445 1437);
PAINT ORANGE (-445 1437);
DISPLAY INVISIBLE (-445 1437);
FORCEPROP 2 LAST CDS_LIB mstr_discrete
J 0
(-450 1375);
PAINT ORANGE (-450 1375);
DISPLAY INVISIBLE (-450 1375);
FORCEPROP 1 LASTPIN (-450 1275) $PN 2
J 0
(-445 1285);
DISPLAY 0.787234 (-445 1285);
PAINT ORANGE (-445 1285);
DISPLAY INVISIBLE (-445 1285);
FORCEADD GND..1
(-450 1200);
FORCEPROP 3 LASTPIN (-450 1250) SIG_NAME GND\g
J 0
(-440 1260);
DISPLAY 0.659574 (-440 1260);
PAINT MONO (-440 1260);
DISPLAY INVISIBLE (-440 1260);
FORCEPROP 1 LAST HDL_POWER GND
J 0
(-450 1350);
DISPLAY 1.723404 (-450 1350);
PAINT GREEN (-450 1350);
DISPLAY INVISIBLE (-450 1350);
FORCEPROP 1 LAST BODY_TYPE PLUMBING
J 0
(-495 1157);
DISPLAY 0.340426 (-495 1157);
PAINT GREEN (-495 1157);
DISPLAY INVISIBLE (-495 1157);
FORCEPROP 1 LAST PATH I92
J 0
(-375 1200);
DISPLAY 0.872340 (-375 1200);
PAINT AQUA (-375 1200);
DISPLAY INVISIBLE (-375 1200);
FORCEPROP 1 LAST SIZE 1B
J 0
(-375 1150);
DISPLAY 1.723404 (-375 1150);
PAINT GREEN (-375 1150);
DISPLAY INVISIBLE (-375 1150);
FORCEPROP 2 LAST CDS_LIB mstr_symbols
J 0
(-450 1200);
PAINT ORANGE (-450 1200);
DISPLAY INVISIBLE (-450 1200);
FORCEPROP 1 LAST VOLTAGE 0
J 0
(-450 1200);
PAINT SKYBLUE (-450 1200);
DISPLAY INVISIBLE (-450 1200);
FORCEPROP 2 LAST ROOM PVCCIN_CPU0_PWR_VR
J 0
(-1000 1275);
DISPLAY 1.936170 (-1000 1275);
PAINT ORANGE (-1000 1275);
DISPLAY INVISIBLE (-1000 1275);
FORCEPROP 2 LAST BOM_COST PROC_VRD_VCCIN_CPU0
J 0
(-825 1275);
DISPLAY 1.446809 (-825 1275);
PAINT MONO (-825 1275);
DISPLAY INVISIBLE (-825 1275);
FORCEADD CAP_A..1
(-4125 675);
FORCEPROP 1 LAST PART_NUMBER A36096-030
J 0
(-4075 525);
DISPLAY 0.617021 (-4075 525);
PAINT BLUE (-4075 525);
FORCEPROP 1 LAST LOCATION CT40
J 0
(-4275 675);
DISPLAY 0.617021 (-4275 675);
PAINT AQUA (-4275 675);
FORCEPROP 0 LAST STATUS NOPOP
J 0
(-4350 575);
DISPLAY 1.021277 (-4350 575);
PAINT ORANGE (-4350 575);
FORCEPROP 1 LAST PACK_TYPE 0402V
J 0
(-4075 475);
DISPLAY 0.617021 (-4075 475);
PAINT SKYBLUE (-4075 475);
FORCEPROP 1 LAST VALUE 0.1UF
J 0
(-4075 725);
DISPLAY 0.617021 (-4075 725);
PAINT SKYBLUE (-4075 725);
FORCEPROP 1 LAST VOLTAGE 16V
J 0
(-4075 675);
DISPLAY 0.617021 (-4075 675);
PAINT SKYBLUE (-4075 675);
FORCEPROP 1 LAST TOLERANCE 10%
J 0
(-4075 625);
DISPLAY 0.617021 (-4075 625);
PAINT SKYBLUE (-4075 625);
FORCEPROP 1 LAST MATERIAL X7R
J 0
(-4075 575);
DISPLAY 0.617021 (-4075 575);
PAINT SKYBLUE (-4075 575);
FORCEPROP 1 LASTPIN (-4125 575) $PN 2
J 0
(-4115 555);
DISPLAY 0.787234 (-4115 555);
PAINT ORANGE (-4115 555);
DISPLAY INVISIBLE (-4115 555);
FORCEPROP 1 LASTPIN (-4125 775) $PN 1
J 0
(-4115 755);
DISPLAY 0.787234 (-4115 755);
PAINT ORANGE (-4115 755);
DISPLAY INVISIBLE (-4115 755);
FORCEPROP 2 LAST CDS_LIB dev_discrete
J 0
(-4125 675);
PAINT MONO (-4125 675);
DISPLAY INVISIBLE (-4125 675);
FORCEPROP 1 LAST PATH I93
J 0
(-4075 825);
DISPLAY 0.978723 (-4075 825);
PAINT WHITE (-4075 825);
DISPLAY INVISIBLE (-4075 825);
FORCEPROP 2 LAST ROOM PVCCIN_CPU0_PWR_VR
J 0
(-4075 825);
DISPLAY 1.361702 (-4075 825);
PAINT ORANGE (-4075 825);
DISPLAY INVISIBLE (-4075 825);
FORCEADD GND..1
(-4125 400);
FORCEPROP 3 LASTPIN (-4125 450) SIG_NAME GND\g
J 0
(-4115 460);
DISPLAY 0.659574 (-4115 460);
PAINT MONO (-4115 460);
DISPLAY INVISIBLE (-4115 460);
FORCEPROP 1 LAST HDL_POWER GND
J 0
(-4125 550);
DISPLAY 1.723404 (-4125 550);
PAINT GREEN (-4125 550);
DISPLAY INVISIBLE (-4125 550);
FORCEPROP 1 LAST BODY_TYPE PLUMBING
J 0
(-4170 357);
DISPLAY 0.340426 (-4170 357);
PAINT GREEN (-4170 357);
DISPLAY INVISIBLE (-4170 357);
FORCEPROP 1 LAST VOLTAGE 0
J 0
(-4125 400);
PAINT SKYBLUE (-4125 400);
DISPLAY INVISIBLE (-4125 400);
FORCEPROP 1 LAST SIZE 1B
J 0
(-4050 350);
DISPLAY 1.723404 (-4050 350);
PAINT GREEN (-4050 350);
DISPLAY INVISIBLE (-4050 350);
FORCEPROP 2 LAST BOM_COST PROC_VRD_VCCIN_CPU0
J 0
(-4500 475);
DISPLAY 1.446809 (-4500 475);
PAINT MONO (-4500 475);
DISPLAY INVISIBLE (-4500 475);
FORCEPROP 2 LAST ROOM PVCCIN_CPU0_PWR_VR
J 0
(-4675 475);
DISPLAY 1.936170 (-4675 475);
PAINT ORANGE (-4675 475);
DISPLAY INVISIBLE (-4675 475);
FORCEPROP 1 LAST PATH I94
J 0
(-4050 400);
DISPLAY 0.872340 (-4050 400);
PAINT AQUA (-4050 400);
DISPLAY INVISIBLE (-4050 400);
FORCEPROP 2 LAST CDS_LIB mstr_symbols
J 0
(-4125 400);
PAINT MONO (-4125 400);
DISPLAY INVISIBLE (-4125 400);
FORCEADD CAP_A..1
(-4125 3375);
FORCEPROP 1 LAST PACK_TYPE 0402V
J 0
(-4075 3175);
DISPLAY 0.617021 (-4075 3175);
PAINT SKYBLUE (-4075 3175);
FORCEPROP 1 LAST VALUE 0.1UF
J 0
(-4075 3425);
DISPLAY 0.617021 (-4075 3425);
PAINT SKYBLUE (-4075 3425);
FORCEPROP 1 LAST PART_NUMBER A36096-030
J 0
(-4075 3225);
DISPLAY 0.617021 (-4075 3225);
PAINT BLUE (-4075 3225);
FORCEPROP 1 LAST MATERIAL X7R
J 0
(-4075 3275);
DISPLAY 0.617021 (-4075 3275);
PAINT SKYBLUE (-4075 3275);
FORCEPROP 1 LAST TOLERANCE 10%
J 0
(-4075 3325);
DISPLAY 0.617021 (-4075 3325);
PAINT SKYBLUE (-4075 3325);
FORCEPROP 1 LAST VOLTAGE 16V
J 0
(-4075 3375);
DISPLAY 0.617021 (-4075 3375);
PAINT SKYBLUE (-4075 3375);
FORCEPROP 1 LAST LOCATION CT39
J 0
(-4300 3375);
DISPLAY 0.617021 (-4300 3375);
PAINT AQUA (-4300 3375);
FORCEPROP 0 LAST STATUS NOPOP
J 0
(-4350 3275);
DISPLAY 1.021277 (-4350 3275);
PAINT ORANGE (-4350 3275);
FORCEPROP 1 LASTPIN (-4125 3275) $PN 2
J 0
(-4115 3255);
DISPLAY 0.787234 (-4115 3255);
PAINT ORANGE (-4115 3255);
DISPLAY INVISIBLE (-4115 3255);
FORCEPROP 1 LASTPIN (-4125 3475) $PN 1
J 0
(-4115 3455);
DISPLAY 0.787234 (-4115 3455);
PAINT ORANGE (-4115 3455);
DISPLAY INVISIBLE (-4115 3455);
FORCEPROP 2 LAST CDS_LIB dev_discrete
J 0
(-4125 3375);
PAINT MONO (-4125 3375);
DISPLAY INVISIBLE (-4125 3375);
FORCEPROP 1 LAST PATH I96
J 0
(-4075 3525);
DISPLAY 0.978723 (-4075 3525);
PAINT WHITE (-4075 3525);
DISPLAY INVISIBLE (-4075 3525);
FORCEPROP 2 LAST ROOM PVCCIN_CPU0_PWR_VR
J 0
(-4075 3525);
DISPLAY 1.361702 (-4075 3525);
PAINT ORANGE (-4075 3525);
DISPLAY INVISIBLE (-4075 3525);
FORCEADD GND..1
(-4125 3125);
FORCEPROP 3 LASTPIN (-4125 3175) SIG_NAME GND\g
J 0
(-4115 3185);
DISPLAY 0.659574 (-4115 3185);
PAINT MONO (-4115 3185);
DISPLAY INVISIBLE (-4115 3185);
FORCEPROP 1 LAST HDL_POWER GND
J 0
(-4125 3275);
DISPLAY 1.723404 (-4125 3275);
PAINT GREEN (-4125 3275);
DISPLAY INVISIBLE (-4125 3275);
FORCEPROP 1 LAST BODY_TYPE PLUMBING
J 0
(-4170 3082);
DISPLAY 0.340426 (-4170 3082);
PAINT GREEN (-4170 3082);
DISPLAY INVISIBLE (-4170 3082);
FORCEPROP 2 LAST CDS_LIB mstr_symbols
J 0
(-4125 3125);
PAINT MONO (-4125 3125);
DISPLAY INVISIBLE (-4125 3125);
FORCEPROP 1 LAST PATH I97
J 0
(-4050 3125);
DISPLAY 0.872340 (-4050 3125);
PAINT AQUA (-4050 3125);
DISPLAY INVISIBLE (-4050 3125);
FORCEPROP 2 LAST ROOM PVCCIN_CPU0_PWR_VR
J 0
(-4675 3200);
DISPLAY 1.936170 (-4675 3200);
PAINT ORANGE (-4675 3200);
DISPLAY INVISIBLE (-4675 3200);
FORCEPROP 2 LAST BOM_COST PROC_VRD_VCCIN_CPU0
J 0
(-4500 3200);
DISPLAY 1.446809 (-4500 3200);
PAINT MONO (-4500 3200);
DISPLAY INVISIBLE (-4500 3200);
FORCEPROP 1 LAST SIZE 1B
J 0
(-4050 3075);
DISPLAY 1.723404 (-4050 3075);
PAINT GREEN (-4050 3075);
DISPLAY INVISIBLE (-4050 3075);
FORCEPROP 1 LAST VOLTAGE 0
J 0
(-4125 3125);
PAINT SKYBLUE (-4125 3125);
DISPLAY INVISIBLE (-4125 3125);
FORCEADD CAP..1
(-2200 3925);
FORCEPROP 1 LAST VALUE 1000PF
J 0
(-2150 3975);
DISPLAY 0.617021 (-2150 3975);
PAINT SKYBLUE (-2150 3975);
FORCEPROP 1 LAST TOLERANCE 10%
J 0
(-2150 3875);
DISPLAY 0.617021 (-2150 3875);
PAINT SKYBLUE (-2150 3875);
FORCEPROP 1 LAST PACK_TYPE 0402LF
J 0
(-2150 3725);
DISPLAY 0.617021 (-2150 3725);
PAINT SKYBLUE (-2150 3725);
FORCEPROP 1 LAST VOLTAGE 50V
J 0
(-2150 3925);
DISPLAY 0.617021 (-2150 3925);
PAINT SKYBLUE (-2150 3925);
FORCEPROP 1 LAST LOCATION CT37
J 0
(-2350 3925);
DISPLAY 0.617021 (-2350 3925);
PAINT AQUA (-2350 3925);
FORCEPROP 1 LAST MATERIAL X7R
J 0
(-2150 3825);
DISPLAY 0.617021 (-2150 3825);
PAINT SKYBLUE (-2150 3825);
FORCEPROP 1 LAST PART_NUMBER A36096-046
J 0
(-2150 3775);
DISPLAY 0.617021 (-2150 3775);
PAINT BLUE (-2150 3775);
FORCEPROP 0 LAST STATUS NOPOP
J 0
(-2475 3850);
DISPLAY 1.021277 (-2475 3850);
PAINT ORANGE (-2475 3850);
FORCEPROP 1 LASTPIN (-2200 4025) $PN 1
J 0
(-2190 4005);
DISPLAY 0.787234 (-2190 4005);
PAINT ORANGE (-2190 4005);
DISPLAY INVISIBLE (-2190 4005);
FORCEPROP 1 LASTPIN (-2200 3825) $PN 2
J 0
(-2190 3805);
DISPLAY 0.787234 (-2190 3805);
PAINT ORANGE (-2190 3805);
DISPLAY INVISIBLE (-2190 3805);
FORCEPROP 2 LAST CDS_LIB mstr_discrete
J 0
(-2200 3925);
PAINT MONO (-2200 3925);
DISPLAY INVISIBLE (-2200 3925);
FORCEPROP 1 LAST PATH I99
J 0
(-2150 4075);
DISPLAY 0.978723 (-2150 4075);
PAINT WHITE (-2150 4075);
DISPLAY INVISIBLE (-2150 4075);
FORCEPROP 0 LAST ROOM VDDQ_KLM_PWR_VR
J 0
(-2150 4125);
DISPLAY 1.021277 (-2150 4125);
PAINT ORANGE (-2150 4125);
DISPLAY INVISIBLE (-2150 4125);
FORCEADD DNS..2
(-445 1370);
PAINT RED (-445 1370);
FORCEPROP 1 LAST COMMENT_BODY TRUE
R 1
J 0
(-370 1145);
DISPLAY 0.872340 (-370 1145);
PAINT GREEN (-370 1145);
DISPLAY INVISIBLE (-370 1145);
FORCEPROP 2 LAST CDS_LIB mstr_misc
J 0
(-445 1370);
PAINT ORANGE (-445 1370);
DISPLAY INVISIBLE (-445 1370);
FORCEADD DNS..2
(-620 4070);
PAINT RED (-620 4070);
FORCEPROP 1 LAST COMMENT_BODY TRUE
R 1
J 0
(-545 3845);
DISPLAY 0.872340 (-545 3845);
PAINT GREEN (-545 3845);
DISPLAY INVISIBLE (-545 3845);
FORCEPROP 2 LAST CDS_LIB mstr_misc
J 0
(-620 4070);
PAINT ORANGE (-620 4070);
DISPLAY INVISIBLE (-620 4070);
FORCEADD INTEL_CORP_BPAGE..1
(0 0);
FORCEPROP 1 LAST CDS_CON_LAST_MODIFIED Tue Dec 01 11:52:21 2015
J 0
(-1425 325);
PAINT GREEN (-1425 325);
DISPLAY INVISIBLE (-1425 325);
FORCEPROP 1 LAST CUSTOM_TXT_CDS <CURRENT_DESIGN_SHEET> OF <TOTAL_DESIGN_SHEETS>
J 0
(-500 25);
PAINT GREEN (-500 25);
FORCEPROP 2 LAST CUSTOM_TXT_CDS <XR_PAGE_TITLE>
J 0
(-7890 5250);
DISPLAY 0.638298 (-7890 5250);
PAINT PINK (-7890 5250);
DISPLAY INVISIBLE (-7890 5250);
FORCEPROP 2 LAST CUSTOM_TXT_CDS <CON_LAST_MODIFIED>
J 0
(-3375 75);
PAINT ORANGE (-3375 75);
FORCEPROP 1 LAST SCH_DEPT BESD
J 1
(-4450 100);
DISPLAY 1.212766 (-4450 100);
PAINT YELLOW (-4450 100);
FORCEPROP 1 LAST SCH_ADDRESS1 2200 Mission College Blvd.
J 0
(-3975 125);
DISPLAY 0.617021 (-3975 125);
PAINT GREEN (-3975 125);
FORCEPROP 1 LAST SCH_NUMBER H4694802
J 0
(-1300 150);
DISPLAY 1.212766 (-1300 150);
PAINT YELLOW (-1300 150);
FORCEPROP 1 LAST SCH_REV 2.420
J 0
(-250 150);
DISPLAY 0.978723 (-250 150);
PAINT YELLOW (-250 150);
FORCEPROP 1 LAST SCH_ADDRESS2 P.O. BOX 58119
J 0
(-3975 75);
DISPLAY 0.617021 (-3975 75);
PAINT GREEN (-3975 75);
FORCEPROP 1 LAST SCH_TITLE VCCIN CPU0 (3 OF 4)
J 0
(-7950 50);
DISPLAY 1.212766 (-7950 50);
PAINT GREEN (-7950 50);
FORCEPROP 1 LAST SCH_ADDRESS3 Santa Clara, CA 95052-8119
J 0
(-3975 25);
DISPLAY 0.617021 (-3975 25);
PAINT GREEN (-3975 25);
FORCEPROP 1 LAST COMMENT_BODY TRUE
J 0
(12 12);
DISPLAY 0.468085 (12 12);
PAINT GREEN (12 12);
DISPLAY INVISIBLE (12 12);
FORCEPROP 2 LAST CDS_LIB mstr_symbols
J 0
(0 0);
PAINT ORANGE (0 0);
DISPLAY INVISIBLE (0 0);
FORCEPROP 2 LAST PAGE_BORDER TRUE
J 0
(-7890 5250);
DISPLAY 0.638298 (-7890 5250);
PAINT PINK (-7890 5250);
DISPLAY INVISIBLE (-7890 5250);
FORCEPROP 2 LAST CDS_XR_PAGE_TITLE CR-203 : @BASEBOARD_FAB2_LIB.BASEBOARD_FAB2(SCH_1):PAGE203
J 0
(-7890 5250);
DISPLAY 0.638298 (-7890 5250);
PAINT PINK (-7890 5250);
DISPLAY INVISIBLE (-7890 5250);
WIRE 16 -1 (-2200 3800)(-2200 3825);
WIRE 16 -1 (-2100 3075)(-2100 3025);
WIRE 16 -1 (-2100 450)(-2100 425);
WIRE 16 -1 (-2150 1150)(-2150 1100);
WIRE 16 -1 (-3850 1325)(-4000 1325);
WIRE 16 -1 (-4000 1325)(-4000 325);
WIRE 16 -1 (-4000 325)(-1350 325);
WIRE 16 -1 (-1350 325)(-1350 900);
WIRE 16 -1 (-1550 900)(-1350 900);
WIRE 16 -1 (-1350 900)(-1025 900);
WIRE 16 -1 (-1025 700)(-1025 900);
WIRE 16 -1 (-750 900)(-1025 900);
WIRE 16 -1 (-750 675)(-750 900);
WIRE 16 -1 (-750 900)(-750 1000);
WIRE 16 -1 (-3825 4050)(-3975 4050);
WIRE 16 -1 (-3975 4050)(-3975 2950);
WIRE 16 -1 (-3975 2950)(-1200 2950);
WIRE 16 -1 (-1200 2950)(-1200 3625);
WIRE 16 -1 (-1450 3625)(-1200 3625);
WIRE 16 -1 (-1025 3625)(-1200 3625);
WIRE 16 -1 (-1025 3475)(-1025 3625);
WIRE 16 -1 (-750 3625)(-1025 3625);
WIRE 16 -1 (-750 3625)(-750 3675);
WIRE 16 -1 (-750 3625)(-750 3475);
WIRE 16 -1 (-750 3275)(-750 3150);
WIRE 16 -1 (-750 3150)(-1025 3150);
WIRE 16 -1 (-1025 3275)(-1025 3150);
WIRE 16 -1 (-1025 3125)(-1025 3150);
WIRE 16 -1 (-3850 2475)(-3850 2325);
WIRE 16 -1 (-3425 2325)(-3850 2325);
WIRE 16 -1 (-3425 2475)(-3425 2325);
WIRE 16 -1 (-2975 2325)(-3425 2325);
WIRE 16 -1 (-2975 2475)(-2975 2325);
WIRE 16 -1 (-2525 2325)(-2975 2325);
WIRE 16 -1 (-2525 2475)(-2525 2325);
WIRE 16 -1 (-2075 2325)(-2525 2325);
WIRE 16 -1 (-2075 2450)(-2075 2325);
WIRE 16 -1 (-1625 2325)(-2075 2325);
WIRE 16 -1 (-1625 2475)(-1625 2325);
WIRE 16 -1 (-1625 2325)(-1150 2325);
WIRE 16 -1 (-1150 2475)(-1150 2325);
WIRE 16 -1 (-1150 2325)(-700 2325);
WIRE 16 -1 (-700 2425)(-700 2325);
WIRE 16 -1 (-700 2325)(-700 2250);
WIRE 16 -1 (-750 475)(-750 425);
WIRE 16 -1 (-750 425)(-1025 425);
WIRE 16 -1 (-1025 425)(-1025 500);
WIRE 16 -1 (-1025 400)(-1025 425);
WIRE 16 -1 (-2825 3500)(-2700 3500);
WIRE 16 -1 (-2700 3500)(-2700 3450);
WIRE 16 -1 (-2825 3450)(-2700 3450);
WIRE 16 -1 (-2700 3400)(-2700 3450);
WIRE 16 -1 (-2825 3400)(-2700 3400);
WIRE 16 -1 (-2700 3350)(-2700 3400);
WIRE 16 -1 (-2825 3350)(-2700 3350);
WIRE 16 -1 (-2700 3300)(-2700 3350);
WIRE 16 -1 (-700 2625)(-700 2750);
WIRE 16 -1 (-700 2750)(-1150 2750);
WIRE 16 -1 (-1150 2675)(-1150 2750);
WIRE 16 -1 (-1625 2750)(-1150 2750);
WIRE 16 -1 (-1625 2675)(-1625 2750);
WIRE 16 -1 (-1625 2750)(-2075 2750);
WIRE 16 -1 (-2075 2650)(-2075 2750);
WIRE 16 -1 (-2075 2750)(-2525 2750);
WIRE 16 -1 (-2525 2675)(-2525 2750);
WIRE 16 -1 (-2525 2750)(-2975 2750);
WIRE 16 -1 (-2975 2675)(-2975 2750);
WIRE 16 -1 (-2975 2750)(-3425 2750);
WIRE 16 -1 (-3425 2675)(-3425 2750);
WIRE 16 -1 (-3425 2750)(-3850 2750);
WIRE 16 -1 (-3850 2675)(-3850 2750);
WIRE 16 -1 (-3850 2750)(-3850 2800);
WIRE 16 -1 (-3825 4400)(-4075 4400);
WIRE 16 -1 (-4075 4400)(-4075 4350);
WIRE 16 -1 (-3825 4350)(-4075 4350);
WIRE 16 -1 (-4075 4350)(-6350 4350);
WIRE 16 -1 (-6350 4250)(-6350 4350);
WIRE 16 -1 (-6350 4350)(-6600 4350);
WIRE 16 -1 (-6600 4250)(-6600 4350);
WIRE 16 -1 (-6600 4350)(-6850 4350);
WIRE 16 -1 (-6850 4275)(-6850 4350);
WIRE 16 -1 (-6850 4350)(-7125 4350);
WIRE 16 -1 (-7125 4250)(-7125 4350);
WIRE 16 -1 (-7125 4350)(-7425 4350);
WIRE 16 -1 (-7425 4250)(-7425 4350);
WIRE 16 -1 (-7425 4550)(-7425 4350);
WIRE 16 -1 (-5300 4025)(-5300 3850);
WIRE 16 -1 (-5300 3850)(-5450 3850);
WIRE 16 -1 (-5450 4050)(-5450 3850);
WIRE 16 -1 (-5450 3850)(-6075 3850);
WIRE 16 -1 (-6075 4025)(-6075 3850);
WIRE 16 -1 (-6075 3850)(-6350 3850);
WIRE 16 -1 (-6350 4050)(-6350 3850);
WIRE 16 -1 (-6350 3850)(-6600 3850);
WIRE 16 -1 (-6600 4050)(-6600 3850);
WIRE 16 -1 (-6600 3850)(-6850 3850);
WIRE 16 -1 (-6850 4075)(-6850 3850);
WIRE 16 -1 (-6850 3850)(-7125 3850);
WIRE 16 -1 (-7125 4050)(-7125 3850);
WIRE 16 -1 (-7125 3850)(-7425 3850);
WIRE 16 -1 (-7425 4050)(-7425 3850);
WIRE 16 -1 (-7425 3800)(-7425 3850);
WIRE 16 -1 (-3850 1625)(-4000 1625);
WIRE 16 -1 (-4000 1675)(-4000 1625);
WIRE 16 -1 (-3850 1675)(-4000 1675);
WIRE 16 -1 (-4000 1675)(-6475 1675);
WIRE 16 -1 (-6475 1550)(-6475 1675);
WIRE 16 -1 (-6475 1675)(-6700 1675);
WIRE 16 -1 (-6700 1500)(-6700 1675);
WIRE 16 -1 (-6700 1675)(-6950 1675);
WIRE 16 -1 (-6950 1500)(-6950 1675);
WIRE 16 -1 (-6950 1675)(-7200 1675);
WIRE 16 -1 (-7200 1550)(-7200 1675);
WIRE 16 -1 (-7200 1675)(-7475 1675);
WIRE 16 -1 (-7475 1550)(-7475 1675);
WIRE 16 -1 (-7475 1850)(-7475 1675);
WIRE 16 -1 (-5525 1375)(-5525 1125);
WIRE 16 -1 (-5525 1125)(-5650 1125);
WIRE 16 -1 (-5650 1375)(-5650 1125);
WIRE 16 -1 (-5650 1125)(-6225 1125);
WIRE 16 -1 (-6225 1350)(-6225 1125);
WIRE 16 -1 (-6225 1125)(-6475 1125);
WIRE 16 -1 (-6475 1350)(-6475 1125);
WIRE 16 -1 (-6475 1125)(-6700 1125);
WIRE 16 -1 (-6700 1300)(-6700 1125);
WIRE 16 -1 (-6700 1125)(-6950 1125);
WIRE 16 -1 (-6950 1300)(-6950 1125);
WIRE 16 -1 (-6950 1125)(-7200 1125);
WIRE 16 -1 (-7200 1350)(-7200 1125);
WIRE 16 -1 (-7200 1125)(-7475 1125);
WIRE 16 -1 (-7475 1350)(-7475 1125);
WIRE 16 -1 (-7475 1075)(-7475 1125);
WIRE 16 -1 (-2850 775)(-2775 775);
WIRE 16 -1 (-2775 725)(-2775 775);
WIRE 16 -1 (-2775 675)(-2775 725);
WIRE 16 -1 (-2775 725)(-2850 725);
WIRE 16 -1 (-2775 625)(-2775 675);
WIRE 16 -1 (-2775 675)(-2850 675);
WIRE 16 -1 (-2775 550)(-2775 625);
WIRE 16 -1 (-2775 625)(-2850 625);
WIRE 16 -1 (-3825 4150)(-4000 4150);
WIRE 16 -1 (-4000 4150)(-4000 4250);
WIRE 16 -1 (-3825 4250)(-4000 4250);
WIRE 16 -1 (-4000 4250)(-4625 4250);
WIRE 16 -1 (-4625 4725)(-4625 4250);
WIRE 16 -1 (-4625 4725)(-5300 4725);
WIRE 16 -1 (-4625 4800)(-4625 4725);
WIRE 16 -1 (-5300 4725)(-5450 4725);
WIRE 16 -1 (-5300 4225)(-5300 4725);
WIRE 16 -1 (-5450 4250)(-5450 4725);
WIRE 16 -1 (-5450 4725)(-5750 4725);
WIRE 16 -1 (-3850 1425)(-3975 1425);
WIRE 16 -1 (-3975 1425)(-3975 1525);
WIRE 16 -1 (-3975 1525)(-3850 1525);
WIRE 16 -1 (-4600 1525)(-3975 1525);
WIRE 16 -1 (-4600 1975)(-4600 1525);
WIRE 16 -1 (-5525 1975)(-4600 1975);
WIRE 16 -1 (-4600 2050)(-4600 1975);
WIRE 16 -1 (-5650 1975)(-5525 1975);
WIRE 16 -1 (-5525 1575)(-5525 1975);
WIRE 16 -1 (-5650 1575)(-5650 1975);
WIRE 16 -1 (-5800 1975)(-5650 1975);
WIRE 16 -1 (-625 3975)(-625 3900);
WIRE 16 -1 (-450 1275)(-450 1250);
WIRE 16 -1 (-4125 450)(-4125 575);
WIRE 16 -1 (-4125 3275)(-4125 3175);
WIRE 3 2175 (-2400 2925)(-1750 2925);
WIRE 3 2175 (-2400 3600)(-2400 2925);
WIRE 3 2175 (-1750 3600)(-1750 2925);
WIRE 3 2175 (-2400 3600)(-1750 3600);
WIRE 3 2175 (-2350 925)(-1875 925);
WIRE 3 2175 (-2350 925)(-2350 350);
WIRE 3 2175 (-1875 925)(-1875 350);
WIRE 3 2175 (-2350 350)(-1875 350);
WIRE 16 -1 (-6100 700)(-4300 700);
FORCEPROP 0 LAST VOLTAGE 5
J 0
(-6025 775);
DISPLAY 1.021277 (-6025 775);
PAINT SKYBLUE (-6025 775);
DISPLAY INVISIBLE (-6025 775);
FORCEPROP 2 LAST SIG_NAME VR_PVCCIN_CPU0_PH4_PHASE
J 0
(-6038 706);
DISPLAY 0.617021 (-6038 706);
PAINT ORANGE (-6038 706);
FORCEPROP 2 LASTPROP $XRERR UNIQUE?
J 0
(-6278 706);
DISPLAY 0.638298 (-6278 706);
PAINT MONO (-6278 706);
DISPLAY INVISIBLE (-6278 706);
WIRE 16 -1 (-4300 700)(-4300 825);
WIRE 16 -1 (-4300 825)(-3850 825);
WIRE 3 2175 (-5400 775)(-4875 775);
WIRE 3 2175 (-5400 1025)(-5400 775);
WIRE 3 2175 (-4875 1025)(-4875 775);
WIRE 3 2175 (-5400 1025)(-4875 1025);
WIRE 16 -1 (-6100 950)(-5275 950);
FORCEPROP 2 LAST SIG_NAME VR_PVCCIN_CPU0_PH4_BOOT
J 0
(-6090 956);
DISPLAY 0.617021 (-6090 956);
PAINT ORANGE (-6090 956);
FORCEPROP 2 LASTPROP $XRERR UNIQUE?
J 0
(-6330 956);
DISPLAY 0.638298 (-6330 956);
PAINT MONO (-6330 956);
DISPLAY INVISIBLE (-6330 956);
WIRE 16 -1 (-6100 900)(-6100 950);
WIRE 16 2175 (-6475 575)(-5500 575);
WIRE 16 2175 (-6475 1000)(-6475 575);
WIRE 16 2175 (-5500 1000)(-5500 575);
WIRE 16 2175 (-6475 1000)(-5500 1000);
WIRE 3 2175 (-2400 1025)(-1900 1025);
WIRE 3 2175 (-2400 1450)(-2400 1025);
WIRE 3 2175 (-1900 1450)(-1900 1025);
WIRE 3 2175 (-2400 1450)(-1900 1450);
WIRE 16 -1 (-2850 1400)(-2150 1400);
FORCEPROP 2 LAST SIG_NAME A_TSENSE_PVCCIN_CPU0
J 0
(-2837 1410);
DISPLAY 0.617021 (-2837 1410);
PAINT ORANGE (-2837 1410);
WIRE 16 -1 (-2850 1400)(-2850 1225);
WIRE 16 -1 (-2150 1400)(-1275 1400);
WIRE 16 -1 (-2150 1350)(-2150 1400);
WIRE 16 -1 (-2825 3625)(-2100 3625);
FORCEPROP 0 LAST VOLTAGE 5
J 0
(-2275 3700);
DISPLAY 1.021277 (-2275 3700);
PAINT SKYBLUE (-2275 3700);
DISPLAY INVISIBLE (-2275 3700);
FORCEPROP 2 LAST SIG_NAME VR_PVCCIN_CPU0_PHASE3
J 0
(-2640 3635);
DISPLAY 0.617021 (-2640 3635);
PAINT ORANGE (-2640 3635);
FORCEPROP 2 LASTPROP $XRERR UNIQUE?
J 0
(-2880 3635);
DISPLAY 0.638298 (-2880 3635);
PAINT MONO (-2880 3635);
DISPLAY INVISIBLE (-2880 3635);
WIRE 16 -1 (-2825 3625)(-2825 3600);
WIRE 16 -1 (-2100 3625)(-1650 3625);
WIRE 16 -1 (-2100 3550)(-2100 3625);
WIRE 3 2175 (-2250 4125)(-1950 4125);
WIRE 3 2175 (-2250 4125)(-2250 3675);
WIRE 3 2175 (-1950 4125)(-1950 3675);
WIRE 3 2175 (-2250 3675)(-1950 3675);
WIRE 3 2175 (-4350 3075)(-3900 3075);
WIRE 3 2175 (-4350 3675)(-4350 3075);
WIRE 3 2175 (-3900 3675)(-3900 3075);
WIRE 3 2175 (-4350 3675)(-3900 3675);
WIRE 16 -1 (-6025 3425)(-4225 3425);
FORCEPROP 0 LAST VOLTAGE 5
J 0
(-5975 3500);
DISPLAY 1.021277 (-5975 3500);
PAINT SKYBLUE (-5975 3500);
DISPLAY INVISIBLE (-5975 3500);
FORCEPROP 2 LAST SIG_NAME VR_PVCCIN_CPU0_PH3_PHASE
J 0
(-5984 3438);
DISPLAY 0.617021 (-5984 3438);
PAINT ORANGE (-5984 3438);
FORCEPROP 2 LASTPROP $XRERR UNIQUE?
J 0
(-6224 3438);
DISPLAY 0.638298 (-6224 3438);
PAINT MONO (-6224 3438);
DISPLAY INVISIBLE (-6224 3438);
WIRE 16 -1 (-4225 3425)(-4225 3550);
WIRE 16 -1 (-4225 3550)(-3825 3550);
WIRE 3 2175 (-5250 3775)(-4775 3775);
WIRE 3 2175 (-5250 3775)(-5250 3525);
WIRE 3 2175 (-4775 3775)(-4775 3525);
WIRE 3 2175 (-5250 3525)(-4775 3525);
WIRE 16 2175 (-6300 3750)(-5450 3750);
WIRE 16 2175 (-6300 3750)(-6300 3325);
WIRE 16 2175 (-5450 3750)(-5450 3325);
WIRE 16 2175 (-6300 3325)(-5450 3325);
WIRE 16 -1 (-5050 3700)(-6025 3700);
FORCEPROP 2 LAST SIG_NAME VR_PVCCIN_CPU0_PH3_BOOT
J 0
(-6025 3713);
DISPLAY 0.617021 (-6025 3713);
PAINT ORANGE (-6025 3713);
FORCEPROP 2 LASTPROP $XRERR UNIQUE?
J 0
(-6265 3713);
DISPLAY 0.638298 (-6265 3713);
PAINT MONO (-6265 3713);
DISPLAY INVISIBLE (-6265 3713);
WIRE 16 -1 (-6025 3700)(-6025 3625);
WIRE 16 -1 (-6750 3800)(-3825 3800);
WIRE 16 -1 (-4675 1175)(-3850 1175);
FORCEPROP 0 LAST SIG_NAME TP_PVCCIN_CPU0_PH4_GL_0
J 0
(-4648 1190);
DISPLAY 0.617021 (-4648 1190);
PAINT ORANGE (-4648 1190);
FORCEPROP 2 LASTPROP $XRERR UNIQUE?
J 0
(-4915 1175);
DISPLAY 0.638298 (-4915 1175);
PAINT MONO (-4915 1175);
DISPLAY INVISIBLE (-4915 1175);
WIRE 3 2175 (-4400 925)(-3775 925);
WIRE 3 2175 (-4400 925)(-4400 375);
WIRE 3 2175 (-3775 925)(-3775 375);
WIRE 3 2175 (-4400 375)(-3775 375);
WIRE 16 -1 (-6725 1075)(-3850 1075);
FORCEPROP 2 LAST SIG_NAME VR_PVCCIN_CPU0_PWM4
J 0
(-6738 1085);
DISPLAY 0.617021 (-6738 1085);
PAINT ORANGE (-6738 1085);
WIRE 16 2175 (-5700 4300)(-5050 4300);
WIRE 16 2175 (-5700 4300)(-5700 3900);
WIRE 16 2175 (-5050 4300)(-5050 3900);
WIRE 16 2175 (-5700 3900)(-5050 3900);
WIRE 16 -1 (-4850 3700)(-4225 3700);
FORCEPROP 2 LAST SIG_NAME VR_PVCCIN_CPU0_PH3_BOOT_R
J 0
(-4750 3713);
DISPLAY 0.617021 (-4750 3713);
PAINT ORANGE (-4750 3713);
FORCEPROP 2 LASTPROP $XRERR UNIQUE?
J 0
(-4990 3713);
DISPLAY 0.638298 (-4990 3713);
PAINT MONO (-4990 3713);
DISPLAY INVISIBLE (-4990 3713);
WIRE 16 -1 (-4225 3700)(-4225 3600);
WIRE 16 -1 (-3825 3600)(-4225 3600);
WIRE 16 -1 (-2850 900)(-2100 900);
FORCEPROP 0 LAST VOLTAGE 5
J 0
(-2425 975);
DISPLAY 1.021277 (-2425 975);
PAINT SKYBLUE (-2425 975);
DISPLAY INVISIBLE (-2425 975);
FORCEPROP 2 LAST SIG_NAME VR_PVCCIN_CPU0_PHASE4
J 0
(-2790 910);
DISPLAY 0.617021 (-2790 910);
PAINT ORANGE (-2790 910);
FORCEPROP 2 LASTPROP $XRERR UNIQUE?
J 0
(-3030 910);
DISPLAY 0.638298 (-3030 910);
PAINT MONO (-3030 910);
DISPLAY INVISIBLE (-3030 910);
WIRE 16 -1 (-2850 900)(-2850 875);
WIRE 16 -1 (-1750 900)(-2100 900);
WIRE 16 -1 (-2100 875)(-2100 900);
WIRE 16 -1 (-2850 1475)(-2225 1475);
FORCEPROP 2 LAST SIG_NAME NC_PVCCIN_CPU0_PH4_P31
J 0
(-2762 1485);
DISPLAY 0.617021 (-2762 1485);
PAINT ORANGE (-2762 1485);
FORCEPROP 2 LASTPROP $XRERR UNIQUE?
J 0
(-2195 1475);
DISPLAY 0.638298 (-2195 1475);
PAINT MONO (-2195 1475);
DISPLAY INVISIBLE (-2195 1475);
WIRE 16 -1 (-1250 2050)(-4125 2050);
FORCEPROP 2 LAST SIG_NAME VR_PVCCIN_CPU0_AIREF4
J 0
(-1852 2058);
DISPLAY 0.617021 (-1852 2058);
PAINT ORANGE (-1852 2058);
WIRE 16 -1 (-4125 2050)(-4125 975);
WIRE 16 -1 (-3850 975)(-4125 975);
WIRE 16 -1 (-4125 975)(-4125 775);
WIRE 16 -1 (-2850 1725)(-1175 1725);
FORCEPROP 2 LAST SIG_NAME ISENSE_PVCCIN_CPU0_PH4_IMON
J 0
(-2640 1735);
DISPLAY 0.617021 (-2640 1735);
PAINT ORANGE (-2640 1735);
WIRE 16 -1 (-2100 3325)(-2100 3400);
WIRE 16 -1 (-6075 4725)(-5950 4725);
FORCEPROP 2 LAST SIG_NAME VR_PVCCIN_CPU0_PH3_VCIN
J 0
(-6044 4460);
DISPLAY 0.617021 (-6044 4460);
PAINT ORANGE (-6044 4460);
FORCEPROP 2 LASTPROP $XRERR UNIQUE?
J 0
(-6284 4460);
DISPLAY 0.638298 (-6284 4460);
PAINT MONO (-6284 4460);
DISPLAY INVISIBLE (-6284 4460);
WIRE 16 -1 (-6075 4725)(-6075 4450);
WIRE 16 -1 (-3825 4450)(-6075 4450);
WIRE 16 -1 (-6075 4450)(-6075 4225);
WIRE 16 -1 (-2825 4250)(-625 4250);
FORCEPROP 0 LAST VOLTAGE 3.6
J 0
(-2750 4325);
DISPLAY 1.021277 (-2750 4325);
PAINT SKYBLUE (-2750 4325);
DISPLAY INVISIBLE (-2750 4325);
FORCEPROP 2 LAST SIG_NAME VR_PVCCIN_CPU0_PH3_OCSET
J 0
(-2693 4266);
DISPLAY 0.617021 (-2693 4266);
PAINT ORANGE (-2693 4266);
FORCEPROP 2 LASTPROP $XRERR UNIQUE?
J 0
(-2933 4266);
DISPLAY 0.638298 (-2933 4266);
PAINT MONO (-2933 4266);
DISPLAY INVISIBLE (-2933 4266);
WIRE 16 -1 (-625 4175)(-625 4250);
WIRE 16 -1 (-2825 4075)(-2200 4075);
FORCEPROP 2 LAST SIG_NAME A_TSENSE_PVCCIN_CPU0
J 0
(-2693 4088);
DISPLAY 0.617021 (-2693 4088);
PAINT ORANGE (-2693 4088);
WIRE 16 -1 (-2825 4075)(-2825 3950);
WIRE 16 -1 (-2200 4075)(-1750 4075);
WIRE 16 -1 (-2200 4025)(-2200 4075);
WIRE 16 -1 (-4550 3950)(-3825 3950);
FORCEPROP 0 LAST SIG_NAME TP_PVCCIN_CPU0_PH3_GL_1
J 0
(-4523 3965);
DISPLAY 0.617021 (-4523 3965);
PAINT ORANGE (-4523 3965);
FORCEPROP 2 LASTPROP $XRERR UNIQUE?
J 0
(-4790 3950);
DISPLAY 0.638298 (-4790 3950);
PAINT MONO (-4790 3950);
DISPLAY INVISIBLE (-4790 3950);
WIRE 16 -1 (-4550 3900)(-3825 3900);
FORCEPROP 0 LAST SIG_NAME TP_PVCCIN_CPU0_PH3_GL_0
J 0
(-4523 3915);
DISPLAY 0.617021 (-4523 3915);
PAINT ORANGE (-4523 3915);
FORCEPROP 2 LASTPROP $XRERR UNIQUE?
J 0
(-4790 3900);
DISPLAY 0.638298 (-4790 3900);
PAINT MONO (-4790 3900);
DISPLAY INVISIBLE (-4790 3900);
WIRE 16 -1 (-5075 950)(-4300 950);
FORCEPROP 2 LAST SIG_NAME VR_PVCCIN_CPU0_PH4_BOOT_R
J 0
(-4865 956);
DISPLAY 0.617021 (-4865 956);
PAINT ORANGE (-4865 956);
FORCEPROP 2 LASTPROP $XRERR UNIQUE?
J 0
(-5105 956);
DISPLAY 0.638298 (-5105 956);
PAINT MONO (-5105 956);
DISPLAY INVISIBLE (-5105 956);
WIRE 16 -1 (-4300 950)(-4300 875);
WIRE 16 -1 (-4300 875)(-3850 875);
WIRE 16 -1 (-6225 1725)(-3850 1725);
FORCEPROP 0 LAST VOLTAGE 5
J 0
(-4450 1800);
DISPLAY 1.021277 (-4450 1800);
PAINT SKYBLUE (-4450 1800);
DISPLAY INVISIBLE (-4450 1800);
FORCEPROP 2 LAST SIG_NAME VR_PVCCIN_CPU0_PH4_VCIN
J 0
(-6114 1735);
DISPLAY 0.617021 (-6114 1735);
PAINT ORANGE (-6114 1735);
FORCEPROP 2 LASTPROP $XRERR UNIQUE?
J 0
(-6354 1735);
DISPLAY 0.638298 (-6354 1735);
PAINT MONO (-6354 1735);
DISPLAY INVISIBLE (-6354 1735);
WIRE 16 -1 (-6225 1975)(-6225 1725);
WIRE 16 -1 (-6225 1550)(-6225 1725);
WIRE 16 -1 (-6225 1975)(-6000 1975);
WIRE 16 -1 (-2825 4200)(-2200 4200);
FORCEPROP 2 LAST SIG_NAME NC_PVCCIN_CPU0_PH3_P31
J 0
(-2691 4210);
DISPLAY 0.617021 (-2691 4210);
PAINT ORANGE (-2691 4210);
FORCEPROP 2 LASTPROP $XRERR UNIQUE?
J 0
(-2170 4200);
DISPLAY 0.638298 (-2170 4200);
PAINT MONO (-2170 4200);
DISPLAY INVISIBLE (-2170 4200);
WIRE 16 -1 (-2100 700)(-2100 725);
WIRE 16 -1 (-2850 1525)(-450 1525);
FORCEPROP 0 LAST VOLTAGE 3.6
J 0
(-2775 1600);
DISPLAY 1.021277 (-2775 1600);
PAINT SKYBLUE (-2775 1600);
DISPLAY INVISIBLE (-2775 1600);
FORCEPROP 2 LAST SIG_NAME VR_PVCCIN_CPU0_PH4_OCSET
J 0
(-2718 1541);
DISPLAY 0.617021 (-2718 1541);
PAINT ORANGE (-2718 1541);
FORCEPROP 2 LASTPROP $XRERR UNIQUE?
J 0
(-2958 1541);
DISPLAY 0.638298 (-2958 1541);
PAINT MONO (-2958 1541);
DISPLAY INVISIBLE (-2958 1541);
WIRE 16 -1 (-450 1525)(-450 1475);
WIRE 16 -1 (-4675 1225)(-3850 1225);
FORCEPROP 0 LAST SIG_NAME TP_PVCCIN_CPU0_PH4_GL_1
J 0
(-4648 1240);
DISPLAY 0.617021 (-4648 1240);
PAINT ORANGE (-4648 1240);
FORCEPROP 2 LASTPROP $XRERR UNIQUE?
J 0
(-4915 1225);
DISPLAY 0.638298 (-4915 1225);
PAINT MONO (-4915 1225);
DISPLAY INVISIBLE (-4915 1225);
WIRE 16 -1 (-1150 4700)(-1675 4700);
FORCEPROP 2 LAST SIG_NAME VR_PVCCIN_CPU0_AIREF3
J 0
(-1654 4706);
DISPLAY 0.617021 (-1654 4706);
PAINT ORANGE (-1654 4706);
WIRE 16 -1 (-1675 4825)(-1675 4700);
WIRE 16 -1 (-4125 4825)(-1675 4825);
WIRE 16 -1 (-4125 3700)(-4125 4825);
WIRE 16 -1 (-3825 3700)(-4125 3700);
WIRE 16 -1 (-4125 3475)(-4125 3700);
WIRE 16 -1 (-2825 4450)(-1050 4450);
FORCEPROP 2 LAST SIG_NAME ISENSE_PVCCIN_CPU0_PH3_IMON
J 0
(-2580 4464);
DISPLAY 0.617021 (-2580 4464);
PAINT ORANGE (-2580 4464);
WIRE 16 2175 (-5950 1275)(-5275 1275);
WIRE 16 2175 (-5950 1650)(-5950 1275);
WIRE 16 2175 (-5275 1650)(-5275 1275);
WIRE 16 2175 (-5950 1650)(-5275 1650);
DOT 1 (-1200 3625);
DOT 1 (-4000 4250);
DOT 1 (-4075 4350);
DOT 1 (-700 2325);
DOT 1 (-1025 3150);
DOT 1 (-1150 2750);
DOT 1 (-1150 2325);
DOT 1 (-1025 425);
DOT 1 (-2700 3350);
DOT 1 (-2700 3450);
DOT 1 (-2700 3400);
DOT 1 (-2525 2750);
DOT 1 (-2075 2325);
DOT 1 (-2525 2325);
DOT 1 (-2975 2325);
DOT 1 (-3425 2750);
DOT 1 (-3425 2325);
DOT 1 (-3850 2750);
DOT 1 (-4000 1675);
DOT 1 (-3975 1525);
DOT 1 (-4625 4725);
DOT 1 (-5450 4725);
DOT 1 (-5300 4725);
DOT 1 (-6075 4450);
DOT 1 (-6350 4350);
DOT 1 (-6600 4350);
DOT 1 (-6850 4350);
DOT 1 (-7125 4350);
DOT 1 (-7425 4350);
DOT 1 (-5450 3850);
DOT 1 (-6075 3850);
DOT 1 (-5525 1975);
DOT 1 (-5650 1975);
DOT 1 (-5650 1125);
DOT 1 (-6350 3850);
DOT 1 (-6600 3850);
DOT 1 (-6850 3850);
DOT 1 (-7125 3850);
DOT 1 (-7425 3850);
DOT 1 (-6475 1675);
DOT 1 (-6225 1125);
DOT 1 (-6475 1125);
DOT 1 (-6700 1675);
DOT 1 (-6950 1675);
DOT 1 (-6700 1125);
DOT 1 (-6950 1125);
DOT 1 (-7200 1675);
DOT 1 (-7475 1675);
DOT 1 (-7200 1125);
DOT 1 (-7475 1125);
DOT 1 (-2200 4075);
DOT 1 (-2150 1400);
DOT 1 (-2075 2750);
DOT 1 (-2975 2750);
DOT 1 (-4125 3700);
DOT 1 (-6225 1725);
DOT 1 (-4125 975);
DOT 1 (-2775 725);
DOT 1 (-2775 675);
DOT 1 (-2100 900);
DOT 1 (-750 900);
DOT 1 (-1350 900);
DOT 1 (-1025 900);
DOT 1 (-2775 625);
DOT 1 (-2100 3625);
DOT 1 (-750 3625);
DOT 1 (-1025 3625);
DOT 1 (-4600 1975);
DOT 1 (-1625 2750);
DOT 1 (-1625 2325);
FORCENOTE
TP FAB1 CO-LAY WITH TI PARTS 11/16
(-3400 425) 0;
DISPLAY LEFT (-3400 425);
DISPLAY 0.851064 (-3400 425);
PAINT RED (-3400 425);
FORCENOTE
TP FAB1 3.01 OHM NEED CHANGE TO 2.2 OHM BUT WAIT FOR SYMBOL
(-3650 375) 0;
DISPLAY LEFT (-3650 375);
DISPLAY 0.680851 (-3650 375);
PAINT RED (-3650 375);
FORCENOTE
TP FAB1 CO-LAY WITH TI PARTS 11/16
(-5375 525) 0;
DISPLAY LEFT (-5375 525);
DISPLAY 0.851064 (-5375 525);
PAINT RED (-5375 525);
FORCENOTE
TP FAB1 CO-LAY WITH TI PARTS 11/16
(-1850 1175) 0;
DISPLAY LEFT (-1850 1175);
DISPLAY 1.021277 (-1850 1175);
PAINT RED (-1850 1175);
FORCENOTE
TP FAB1 CO-LAY WITH TI PARTS 11/16
(-1925 3850) 0;
DISPLAY LEFT (-1925 3850);
DISPLAY 1.021277 (-1925 3850);
PAINT RED (-1925 3850);
FORCENOTE
TP FAB1 CO-LAY WITH TI PARTS 11/16
(-1725 2900) 0;
DISPLAY LEFT (-1725 2900);
DISPLAY 1.021277 (-1725 2900);
PAINT RED (-1725 2900);
FORCENOTE
TP FAB1 3.01 OHM NEED CHANGE TO 2.2 OHM BUT WAIT FOR SYMBOL
(-1725 2850) 0;
DISPLAY LEFT (-1725 2850);
DISPLAY 1.021277 (-1725 2850);
PAINT RED (-1725 2850);
FORCENOTE
ROOM = PVCCIN_CPU0_DECAP_VR
(-3390 2765) 0;
DISPLAY LEFT (-3390 2765);
DISPLAY 1.191489 (-3390 2765);
PAINT PURPLE (-3390 2765);
FORCENOTE
TP FAB1 CO-LAY WITH TI PARTS 11/16
(-5300 3275) 0;
DISPLAY LEFT (-5300 3275);
DISPLAY 0.851064 (-5300 3275);
PAINT RED (-5300 3275);
FORCENOTE
ROOM=PVCCIN_CPU0_PWR_VR
(-7255 3010) 0;
DISPLAY LEFT (-7255 3010);
DISPLAY 2.446809 (-7255 3010);
PAINT PURPLE (-7255 3010);
FORCENOTE
PLACE ON TOP
(-5705 3825) 0;
DISPLAY LEFT (-5705 3825);
DISPLAY 1.553191 (-5705 3825);
PAINT PURPLE (-5705 3825);
FORCENOTE
PLACE ON TOP
(-5980 1175) 0;
DISPLAY LEFT (-5980 1175);
DISPLAY 1.553191 (-5980 1175);
PAINT PURPLE (-5980 1175);
FORCENOTE
SPOF
(-6005 500) 0;
DISPLAY LEFT (-6005 500);
DISPLAY 1.808511 (-6005 500);
PAINT PURPLE (-6005 500);
FORCENOTE
SPOF
(-6080 3225) 0;
DISPLAY LEFT (-6080 3225);
DISPLAY 1.936170 (-6080 3225);
PAINT PURPLE (-6080 3225);
FORCENOTE
ROOM=PVCCIN_CPU0_PWR_VR
(-7705 285) 0;
DISPLAY LEFT (-7705 285);
DISPLAY 2.446809 (-7705 285);
PAINT PURPLE (-7705 285);
QUIT
